FILE_TYPE = MACRO_DRAWING;
SET COLOR_WIRE YELLOW;
SET COLOR_PROP ORANGE;
SET COLOR_DOT WHITE;
SET COLOR_ARC YELLOW;
SET COLOR_BODY GREEN;
SET COLOR_NOTE PURPLE;
SET PROP_DISPLAY VALUE;
SET PAGE_NUMBER P71;
FORCEADD UNIVERSAL_GND..1
(-3825 -775);
FORCEPROP 3 LASTPIN (-3825 -725) SIG_NAME GND\g
J 0
(-3815 -715);
DISPLAY 0.659574 (-3815 -715);
PAINT MONO (-3815 -715);
DISPLAY INVISIBLE (-3815 -715);
FORCEPROP 2 LAST CDS_LIB logical_power
J 0
(-3825 -775);
PAINT MONO (-3825 -775);
DISPLAY INVISIBLE (-3825 -775);
FORCEPROP 1 LAST HDL_POWER GND
J 1
(-3800 -850);
DISPLAY 0.872340 (-3800 -850);
PAINT GREEN (-3800 -850);
DISPLAY INVISIBLE (-3800 -850);
FORCEPROP 1 LAST PATH I1
J 0
(-3750 -775);
DISPLAY 0.872340 (-3750 -775);
PAINT AQUA (-3750 -775);
DISPLAY INVISIBLE (-3750 -775);
FORCEADD SOCKET4677_AZIF0045P001C01CS..34
(-2375 1750);
FORCEPROP 1 LAST PART_NUMBER DGA^7000023
J 0
(-3425 4000);
DISPLAY 0.723404 (-3425 4000);
PAINT GREEN (-3425 4000);
DISPLAY INVISIBLE (-3425 4000);
FORCEPROP 2 LAST PART_TYPE SMLF
J 0
(-3425 4175);
DISPLAY 1.021277 (-3425 4175);
FORCEPROP 1 LAST MATERIAL IO
J 0
(-3425 3925);
DISPLAY 0.723404 (-3425 3925);
PAINT GREEN (-3425 3925);
FORCEPROP 2 LAST VALUE SOCKET4677_AZIF0045-P001C01CS
J 0
(-3425 4125);
DISPLAY 1.021277 (-3425 4125);
FORCEPROP 1 LAST $LOCATION U1
J 0
(-3425 4075);
DISPLAY 0.723404 (-3425 4075);
PAINT GREEN (-3425 4075);
FORCEPROP 0 LASTPIN (-1175 -225) $PN DB91
J 0
(-1165 -215);
DISPLAY 0.680851 (-1165 -215);
PAINT MONO (-1165 -215);
FORCEPROP 0 LASTPIN (-1175 -175) $PN DC1
J 0
(-1165 -165);
DISPLAY 0.680851 (-1165 -165);
PAINT MONO (-1165 -165);
FORCEPROP 0 LASTPIN (-1175 -25) $PN DC13
J 0
(-1165 -15);
DISPLAY 0.680851 (-1165 -15);
PAINT MONO (-1165 -15);
FORCEPROP 0 LASTPIN (-1175 25) $PN DC21
J 0
(-1165 35);
DISPLAY 0.680851 (-1165 35);
PAINT MONO (-1165 35);
FORCEPROP 0 LASTPIN (-1175 275) $PN DC52
J 0
(-1165 285);
DISPLAY 0.680851 (-1165 285);
PAINT MONO (-1165 285);
FORCEPROP 0 LASTPIN (-1175 325) $PN DC58
J 0
(-1165 335);
DISPLAY 0.680851 (-1165 335);
PAINT MONO (-1165 335);
FORCEPROP 0 LASTPIN (-1175 375) $PN DC64
J 0
(-1165 385);
DISPLAY 0.680851 (-1165 385);
PAINT MONO (-1165 385);
FORCEPROP 0 LASTPIN (-1175 825) $PN DD12
J 0
(-1165 835);
DISPLAY 0.680851 (-1165 835);
PAINT MONO (-1165 835);
FORCEPROP 0 LASTPIN (-1175 875) $PN DD16
J 0
(-1165 885);
DISPLAY 0.680851 (-1165 885);
PAINT MONO (-1165 885);
FORCEPROP 0 LASTPIN (-1175 925) $PN DD49
J 0
(-1165 935);
DISPLAY 0.680851 (-1165 935);
PAINT MONO (-1165 935);
FORCEPROP 0 LASTPIN (-1175 1575) $PN DE39
J 0
(-1165 1585);
DISPLAY 0.680851 (-1165 1585);
PAINT MONO (-1165 1585);
FORCEPROP 0 LASTPIN (-1175 2325) $PN DE70
J 0
(-1165 2335);
DISPLAY 0.680851 (-1165 2335);
PAINT MONO (-1165 2335);
FORCEPROP 0 LASTPIN (-1175 2775) $PN DF12
J 0
(-1165 2785);
DISPLAY 0.680851 (-1165 2785);
PAINT MONO (-1165 2785);
FORCEPROP 0 LASTPIN (-1175 2825) $PN DF16
J 0
(-1165 2835);
DISPLAY 0.680851 (-1165 2835);
PAINT MONO (-1165 2835);
FORCEPROP 0 LASTPIN (-1175 2875) $PN DF49
J 0
(-1165 2885);
DISPLAY 0.680851 (-1165 2885);
PAINT MONO (-1165 2885);
FORCEPROP 0 LASTPIN (-1175 3025) $PN DF91
J 0
(-1165 3035);
DISPLAY 0.680851 (-1165 3035);
PAINT MONO (-1165 3035);
FORCEPROP 0 LASTPIN (-1175 3075) $PN DG1
J 0
(-1165 3085);
DISPLAY 0.680851 (-1165 3085);
PAINT MONO (-1165 3085);
FORCEPROP 0 LASTPIN (-1175 3225) $PN DG13
J 0
(-1165 3235);
DISPLAY 0.680851 (-1165 3235);
PAINT MONO (-1165 3235);
FORCEPROP 0 LASTPIN (-1175 3275) $PN DG21
J 0
(-1165 3285);
DISPLAY 0.680851 (-1165 3285);
PAINT MONO (-1165 3285);
FORCEPROP 0 LASTPIN (-1175 3525) $PN DG52
J 0
(-1165 3535);
DISPLAY 0.680851 (-1165 3535);
PAINT MONO (-1165 3535);
FORCEPROP 0 LASTPIN (-1175 3575) $PN DG58
J 0
(-1165 3585);
DISPLAY 0.680851 (-1165 3585);
PAINT MONO (-1165 3585);
FORCEPROP 0 LASTPIN (-1175 3625) $PN DG64
J 0
(-1165 3635);
DISPLAY 0.680851 (-1165 3635);
PAINT MONO (-1165 3635);
FORCEPROP 0 LASTPIN (-3575 75) $PN DH16
J 2
(-3585 85);
DISPLAY 0.680851 (-3585 85);
PAINT MONO (-3585 85);
FORCEPROP 0 LASTPIN (-3575 125) $PN DH20
J 2
(-3585 135);
DISPLAY 0.680851 (-3585 135);
PAINT MONO (-3585 135);
FORCEPROP 0 LASTPIN (-3575 225) $PN DH26
J 2
(-3585 235);
DISPLAY 0.680851 (-3585 235);
PAINT MONO (-3585 235);
FORCEPROP 0 LASTPIN (-3575 375) $PN DH34
J 2
(-3585 385);
DISPLAY 0.680851 (-3585 385);
PAINT MONO (-3585 385);
FORCEPROP 0 LASTPIN (-3575 525) $PN DH44
J 2
(-3585 535);
DISPLAY 0.680851 (-3585 535);
PAINT MONO (-3585 535);
FORCEPROP 0 LASTPIN (-3575 625) $PN DH51
J 2
(-3585 635);
DISPLAY 0.680851 (-3585 635);
PAINT MONO (-3585 635);
FORCEPROP 0 LASTPIN (-3575 675) $PN DH53
J 2
(-3585 685);
DISPLAY 0.680851 (-3585 685);
PAINT MONO (-3585 685);
FORCEPROP 0 LASTPIN (-3575 775) $PN DH59
J 2
(-3585 785);
DISPLAY 0.680851 (-3585 785);
PAINT MONO (-3585 785);
FORCEPROP 0 LASTPIN (-3575 825) $PN DH63
J 2
(-3585 835);
DISPLAY 0.680851 (-3585 835);
PAINT MONO (-3585 835);
FORCEPROP 0 LASTPIN (-3575 925) $PN DH69
J 2
(-3585 935);
DISPLAY 0.680851 (-3585 935);
PAINT MONO (-3585 935);
FORCEPROP 0 LASTPIN (-3575 1025) $PN DH75
J 2
(-3585 1035);
DISPLAY 0.680851 (-3585 1035);
PAINT MONO (-3585 1035);
FORCEPROP 0 LASTPIN (-3575 1275) $PN DJ25
J 2
(-3585 1285);
DISPLAY 0.680851 (-3585 1285);
PAINT MONO (-3585 1285);
FORCEPROP 0 LASTPIN (-3575 1425) $PN DJ35
J 2
(-3585 1435);
DISPLAY 0.680851 (-3585 1435);
PAINT MONO (-3585 1435);
FORCEPROP 0 LASTPIN (-3575 1725) $PN DJ54
J 2
(-3585 1735);
DISPLAY 0.680851 (-3585 1735);
PAINT MONO (-3585 1735);
FORCEPROP 0 LASTPIN (-3575 1875) $PN DJ62
J 2
(-3585 1885);
DISPLAY 0.680851 (-3585 1885);
PAINT MONO (-3585 1885);
FORCEPROP 0 LASTPIN (-3575 1975) $PN DJ68
J 2
(-3585 1985);
DISPLAY 0.680851 (-3585 1985);
PAINT MONO (-3585 1985);
FORCEPROP 0 LASTPIN (-3575 2425) $PN DK12
J 2
(-3585 2435);
DISPLAY 0.680851 (-3585 2435);
PAINT MONO (-3585 2435);
FORCEPROP 0 LASTPIN (-3575 2525) $PN DK18
J 2
(-3585 2535);
DISPLAY 0.680851 (-3585 2535);
PAINT MONO (-3585 2535);
FORCEPROP 0 LASTPIN (-3575 2575) $PN DK24
J 2
(-3585 2585);
DISPLAY 0.680851 (-3585 2585);
PAINT MONO (-3585 2585);
FORCEPROP 0 LASTPIN (-3575 2725) $PN DK42
J 2
(-3585 2735);
DISPLAY 0.680851 (-3585 2735);
PAINT MONO (-3585 2735);
FORCEPROP 0 LASTPIN (-3575 2825) $PN DK55
J 2
(-3585 2835);
DISPLAY 0.680851 (-3585 2835);
PAINT MONO (-3585 2835);
FORCEPROP 0 LASTPIN (-3575 2875) $PN DK61
J 2
(-3585 2885);
DISPLAY 0.680851 (-3585 2885);
PAINT MONO (-3585 2885);
FORCEPROP 0 LASTPIN (-3575 2925) $PN DK67
J 2
(-3585 2935);
DISPLAY 0.680851 (-3585 2935);
PAINT MONO (-3585 2935);
FORCEPROP 0 LASTPIN (-3575 3325) $PN DL1
J 2
(-3585 3335);
DISPLAY 0.680851 (-3585 3335);
PAINT MONO (-3585 3335);
FORCEPROP 0 LASTPIN (-3575 3475) $PN DL13
J 2
(-3585 3485);
DISPLAY 0.680851 (-3585 3485);
PAINT MONO (-3585 3485);
FORCEPROP 0 LASTPIN (-3575 3525) $PN DL17
J 2
(-3585 3535);
DISPLAY 0.680851 (-3585 3535);
PAINT MONO (-3585 3535);
FORCEPROP 0 LASTPIN (-3575 3375) $PN DL5
J 2
(-3585 3385);
DISPLAY 0.680851 (-3585 3385);
PAINT MONO (-3585 3385);
FORCEPROP 0 LASTPIN (-3575 3625) $PN DL52
J 2
(-3585 3635);
DISPLAY 0.680851 (-3585 3635);
PAINT MONO (-3585 3635);
FORCEPROP 0 LASTPIN (-1175 75) $PN DC27
J 0
(-1165 85);
DISPLAY 0.680851 (-1165 85);
PAINT MONO (-1165 85);
FORCEPROP 0 LASTPIN (-1175 125) $PN DC33
J 0
(-1165 135);
DISPLAY 0.680851 (-1165 135);
PAINT MONO (-1165 135);
FORCEPROP 0 LASTPIN (-1175 175) $PN DC39
J 0
(-1165 185);
DISPLAY 0.680851 (-1165 185);
PAINT MONO (-1165 185);
FORCEPROP 0 LASTPIN (-1175 225) $PN DC45
J 0
(-1165 235);
DISPLAY 0.680851 (-1165 235);
PAINT MONO (-1165 235);
FORCEPROP 0 LASTPIN (-1175 -125) $PN DC5
J 0
(-1165 -115);
DISPLAY 0.680851 (-1165 -115);
PAINT MONO (-1165 -115);
FORCEPROP 0 LASTPIN (-1175 425) $PN DC70
J 0
(-1165 435);
DISPLAY 0.680851 (-1165 435);
PAINT MONO (-1165 435);
FORCEPROP 0 LASTPIN (-1175 475) $PN DC76
J 0
(-1165 485);
DISPLAY 0.680851 (-1165 485);
PAINT MONO (-1165 485);
FORCEPROP 0 LASTPIN (-1175 525) $PN DC78
J 0
(-1165 535);
DISPLAY 0.680851 (-1165 535);
PAINT MONO (-1165 535);
FORCEPROP 0 LASTPIN (-1175 575) $PN DC80
J 0
(-1165 585);
DISPLAY 0.680851 (-1165 585);
PAINT MONO (-1165 585);
FORCEPROP 0 LASTPIN (-1175 625) $PN DC84
J 0
(-1165 635);
DISPLAY 0.680851 (-1165 635);
PAINT MONO (-1165 635);
FORCEPROP 0 LASTPIN (-1175 675) $PN DC88
J 0
(-1165 685);
DISPLAY 0.680851 (-1165 685);
PAINT MONO (-1165 685);
FORCEPROP 0 LASTPIN (-1175 -75) $PN DC9
J 0
(-1165 -65);
DISPLAY 0.680851 (-1165 -65);
PAINT MONO (-1165 -65);
FORCEPROP 0 LASTPIN (-1175 725) $PN DD4
J 0
(-1165 735);
DISPLAY 0.680851 (-1165 735);
PAINT MONO (-1165 735);
FORCEPROP 0 LASTPIN (-1175 975) $PN DD79
J 0
(-1165 985);
DISPLAY 0.680851 (-1165 985);
PAINT MONO (-1165 985);
FORCEPROP 0 LASTPIN (-1175 775) $PN DD8
J 0
(-1165 785);
DISPLAY 0.680851 (-1165 785);
PAINT MONO (-1165 785);
FORCEPROP 0 LASTPIN (-1175 1025) $PN DE17
J 0
(-1165 1035);
DISPLAY 0.680851 (-1165 1035);
PAINT MONO (-1165 1035);
FORCEPROP 0 LASTPIN (-1175 1075) $PN DE19
J 0
(-1165 1085);
DISPLAY 0.680851 (-1165 1085);
PAINT MONO (-1165 1085);
FORCEPROP 0 LASTPIN (-1175 1125) $PN DE21
J 0
(-1165 1135);
DISPLAY 0.680851 (-1165 1135);
PAINT MONO (-1165 1135);
FORCEPROP 0 LASTPIN (-1175 1175) $PN DE23
J 0
(-1165 1185);
DISPLAY 0.680851 (-1165 1185);
PAINT MONO (-1165 1185);
FORCEPROP 0 LASTPIN (-1175 1225) $PN DE25
J 0
(-1165 1235);
DISPLAY 0.680851 (-1165 1235);
PAINT MONO (-1165 1235);
FORCEPROP 0 LASTPIN (-1175 1275) $PN DE27
J 0
(-1165 1285);
DISPLAY 0.680851 (-1165 1285);
PAINT MONO (-1165 1285);
FORCEPROP 0 LASTPIN (-1175 1325) $PN DE29
J 0
(-1165 1335);
DISPLAY 0.680851 (-1165 1335);
PAINT MONO (-1165 1335);
FORCEPROP 0 LASTPIN (-1175 1375) $PN DE31
J 0
(-1165 1385);
DISPLAY 0.680851 (-1165 1385);
PAINT MONO (-1165 1385);
FORCEPROP 0 LASTPIN (-1175 1425) $PN DE33
J 0
(-1165 1435);
DISPLAY 0.680851 (-1165 1435);
PAINT MONO (-1165 1435);
FORCEPROP 0 LASTPIN (-1175 1475) $PN DE35
J 0
(-1165 1485);
DISPLAY 0.680851 (-1165 1485);
PAINT MONO (-1165 1485);
FORCEPROP 0 LASTPIN (-1175 1525) $PN DE37
J 0
(-1165 1535);
DISPLAY 0.680851 (-1165 1535);
PAINT MONO (-1165 1535);
FORCEPROP 0 LASTPIN (-1175 1625) $PN DE41
J 0
(-1165 1635);
DISPLAY 0.680851 (-1165 1635);
PAINT MONO (-1165 1635);
FORCEPROP 0 LASTPIN (-1175 1675) $PN DE43
J 0
(-1165 1685);
DISPLAY 0.680851 (-1165 1685);
PAINT MONO (-1165 1685);
FORCEPROP 0 LASTPIN (-1175 1725) $PN DE45
J 0
(-1165 1735);
DISPLAY 0.680851 (-1165 1735);
PAINT MONO (-1165 1735);
FORCEPROP 0 LASTPIN (-1175 1775) $PN DE48
J 0
(-1165 1785);
DISPLAY 0.680851 (-1165 1785);
PAINT MONO (-1165 1785);
FORCEPROP 0 LASTPIN (-1175 1825) $PN DE50
J 0
(-1165 1835);
DISPLAY 0.680851 (-1165 1835);
PAINT MONO (-1165 1835);
FORCEPROP 0 LASTPIN (-1175 1875) $PN DE52
J 0
(-1165 1885);
DISPLAY 0.680851 (-1165 1885);
PAINT MONO (-1165 1885);
FORCEPROP 0 LASTPIN (-1175 1925) $PN DE54
J 0
(-1165 1935);
DISPLAY 0.680851 (-1165 1935);
PAINT MONO (-1165 1935);
FORCEPROP 0 LASTPIN (-1175 1975) $PN DE56
J 0
(-1165 1985);
DISPLAY 0.680851 (-1165 1985);
PAINT MONO (-1165 1985);
FORCEPROP 0 LASTPIN (-1175 2025) $PN DE58
J 0
(-1165 2035);
DISPLAY 0.680851 (-1165 2035);
PAINT MONO (-1165 2035);
FORCEPROP 0 LASTPIN (-1175 2075) $PN DE60
J 0
(-1165 2085);
DISPLAY 0.680851 (-1165 2085);
PAINT MONO (-1165 2085);
FORCEPROP 0 LASTPIN (-1175 2125) $PN DE62
J 0
(-1165 2135);
DISPLAY 0.680851 (-1165 2135);
PAINT MONO (-1165 2135);
FORCEPROP 0 LASTPIN (-1175 2175) $PN DE64
J 0
(-1165 2185);
DISPLAY 0.680851 (-1165 2185);
PAINT MONO (-1165 2185);
FORCEPROP 0 LASTPIN (-1175 2225) $PN DE66
J 0
(-1165 2235);
DISPLAY 0.680851 (-1165 2235);
PAINT MONO (-1165 2235);
FORCEPROP 0 LASTPIN (-1175 2275) $PN DE68
J 0
(-1165 2285);
DISPLAY 0.680851 (-1165 2285);
PAINT MONO (-1165 2285);
FORCEPROP 0 LASTPIN (-1175 2375) $PN DE72
J 0
(-1165 2385);
DISPLAY 0.680851 (-1165 2385);
PAINT MONO (-1165 2385);
FORCEPROP 0 LASTPIN (-1175 2425) $PN DE74
J 0
(-1165 2435);
DISPLAY 0.680851 (-1165 2435);
PAINT MONO (-1165 2435);
FORCEPROP 0 LASTPIN (-1175 2475) $PN DE76
J 0
(-1165 2485);
DISPLAY 0.680851 (-1165 2485);
PAINT MONO (-1165 2485);
FORCEPROP 0 LASTPIN (-1175 2525) $PN DE82
J 0
(-1165 2535);
DISPLAY 0.680851 (-1165 2535);
PAINT MONO (-1165 2535);
FORCEPROP 0 LASTPIN (-1175 2575) $PN DE84
J 0
(-1165 2585);
DISPLAY 0.680851 (-1165 2585);
PAINT MONO (-1165 2585);
FORCEPROP 0 LASTPIN (-1175 2625) $PN DE88
J 0
(-1165 2635);
DISPLAY 0.680851 (-1165 2635);
PAINT MONO (-1165 2635);
FORCEPROP 0 LASTPIN (-1175 2675) $PN DF4
J 0
(-1165 2685);
DISPLAY 0.680851 (-1165 2685);
PAINT MONO (-1165 2685);
FORCEPROP 0 LASTPIN (-1175 2925) $PN DF79
J 0
(-1165 2935);
DISPLAY 0.680851 (-1165 2935);
PAINT MONO (-1165 2935);
FORCEPROP 0 LASTPIN (-1175 2725) $PN DF8
J 0
(-1165 2735);
DISPLAY 0.680851 (-1165 2735);
PAINT MONO (-1165 2735);
FORCEPROP 0 LASTPIN (-1175 2975) $PN DF87
J 0
(-1165 2985);
DISPLAY 0.680851 (-1165 2985);
PAINT MONO (-1165 2985);
FORCEPROP 0 LASTPIN (-1175 3325) $PN DG27
J 0
(-1165 3335);
DISPLAY 0.680851 (-1165 3335);
PAINT MONO (-1165 3335);
FORCEPROP 0 LASTPIN (-1175 3375) $PN DG33
J 0
(-1165 3385);
DISPLAY 0.680851 (-1165 3385);
PAINT MONO (-1165 3385);
FORCEPROP 0 LASTPIN (-1175 3425) $PN DG39
J 0
(-1165 3435);
DISPLAY 0.680851 (-1165 3435);
PAINT MONO (-1165 3435);
FORCEPROP 0 LASTPIN (-1175 3475) $PN DG45
J 0
(-1165 3485);
DISPLAY 0.680851 (-1165 3485);
PAINT MONO (-1165 3485);
FORCEPROP 0 LASTPIN (-1175 3125) $PN DG5
J 0
(-1165 3135);
DISPLAY 0.680851 (-1165 3135);
PAINT MONO (-1165 3135);
FORCEPROP 0 LASTPIN (-1175 3675) $PN DG70
J 0
(-1165 3685);
DISPLAY 0.680851 (-1165 3685);
PAINT MONO (-1165 3685);
FORCEPROP 0 LASTPIN (-1175 3725) $PN DG76
J 0
(-1165 3735);
DISPLAY 0.680851 (-1165 3735);
PAINT MONO (-1165 3735);
FORCEPROP 0 LASTPIN (-3575 -225) $PN DG80
J 2
(-3585 -215);
DISPLAY 0.680851 (-3585 -215);
PAINT MONO (-3585 -215);
FORCEPROP 0 LASTPIN (-3575 -175) $PN DG84
J 2
(-3585 -165);
DISPLAY 0.680851 (-3585 -165);
PAINT MONO (-3585 -165);
FORCEPROP 0 LASTPIN (-3575 -125) $PN DG88
J 2
(-3585 -115);
DISPLAY 0.680851 (-3585 -115);
PAINT MONO (-3585 -115);
FORCEPROP 0 LASTPIN (-1175 3175) $PN DG9
J 0
(-1165 3185);
DISPLAY 0.680851 (-1165 3185);
PAINT MONO (-1165 3185);
FORCEPROP 0 LASTPIN (-3575 25) $PN DH12
J 2
(-3585 35);
DISPLAY 0.680851 (-3585 35);
PAINT MONO (-3585 35);
FORCEPROP 0 LASTPIN (-3575 175) $PN DH22
J 2
(-3585 185);
DISPLAY 0.680851 (-3585 185);
PAINT MONO (-3585 185);
FORCEPROP 0 LASTPIN (-3575 275) $PN DH28
J 2
(-3585 285);
DISPLAY 0.680851 (-3585 285);
PAINT MONO (-3585 285);
FORCEPROP 0 LASTPIN (-3575 325) $PN DH32
J 2
(-3585 335);
DISPLAY 0.680851 (-3585 335);
PAINT MONO (-3585 335);
FORCEPROP 0 LASTPIN (-3575 425) $PN DH38
J 2
(-3585 435);
DISPLAY 0.680851 (-3585 435);
PAINT MONO (-3585 435);
FORCEPROP 0 LASTPIN (-3575 -75) $PN DH4
J 2
(-3585 -65);
DISPLAY 0.680851 (-3585 -65);
PAINT MONO (-3585 -65);
FORCEPROP 0 LASTPIN (-3575 475) $PN DH40
J 2
(-3585 485);
DISPLAY 0.680851 (-3585 485);
PAINT MONO (-3585 485);
FORCEPROP 0 LASTPIN (-3575 575) $PN DH47
J 2
(-3585 585);
DISPLAY 0.680851 (-3585 585);
PAINT MONO (-3585 585);
FORCEPROP 0 LASTPIN (-3575 725) $PN DH57
J 2
(-3585 735);
DISPLAY 0.680851 (-3585 735);
PAINT MONO (-3585 735);
FORCEPROP 0 LASTPIN (-3575 875) $PN DH65
J 2
(-3585 885);
DISPLAY 0.680851 (-3585 885);
PAINT MONO (-3585 885);
FORCEPROP 0 LASTPIN (-3575 975) $PN DH71
J 2
(-3585 985);
DISPLAY 0.680851 (-3585 985);
PAINT MONO (-3585 985);
FORCEPROP 0 LASTPIN (-3575 1075) $PN DH77
J 2
(-3585 1085);
DISPLAY 0.680851 (-3585 1085);
PAINT MONO (-3585 1085);
FORCEPROP 0 LASTPIN (-3575 -25) $PN DH8
J 2
(-3585 -15);
DISPLAY 0.680851 (-3585 -15);
PAINT MONO (-3585 -15);
FORCEPROP 0 LASTPIN (-3575 1125) $PN DH85
J 2
(-3585 1135);
DISPLAY 0.680851 (-3585 1135);
PAINT MONO (-3585 1135);
FORCEPROP 0 LASTPIN (-3575 1175) $PN DJ19
J 2
(-3585 1185);
DISPLAY 0.680851 (-3585 1185);
PAINT MONO (-3585 1185);
FORCEPROP 0 LASTPIN (-3575 1225) $PN DJ23
J 2
(-3585 1235);
DISPLAY 0.680851 (-3585 1235);
PAINT MONO (-3585 1235);
FORCEPROP 0 LASTPIN (-3575 1325) $PN DJ29
J 2
(-3585 1335);
DISPLAY 0.680851 (-3585 1335);
PAINT MONO (-3585 1335);
FORCEPROP 0 LASTPIN (-3575 1375) $PN DJ31
J 2
(-3585 1385);
DISPLAY 0.680851 (-3585 1385);
PAINT MONO (-3585 1385);
FORCEPROP 0 LASTPIN (-3575 1475) $PN DJ37
J 2
(-3585 1485);
DISPLAY 0.680851 (-3585 1485);
PAINT MONO (-3585 1485);
FORCEPROP 0 LASTPIN (-3575 1525) $PN DJ41
J 2
(-3585 1535);
DISPLAY 0.680851 (-3585 1535);
PAINT MONO (-3585 1535);
FORCEPROP 0 LASTPIN (-3575 1575) $PN DJ43
J 2
(-3585 1585);
DISPLAY 0.680851 (-3585 1585);
PAINT MONO (-3585 1585);
FORCEPROP 0 LASTPIN (-3575 1625) $PN DJ48
J 2
(-3585 1635);
DISPLAY 0.680851 (-3585 1635);
PAINT MONO (-3585 1635);
FORCEPROP 0 LASTPIN (-3575 1675) $PN DJ50
J 2
(-3585 1685);
DISPLAY 0.680851 (-3585 1685);
PAINT MONO (-3585 1685);
FORCEPROP 0 LASTPIN (-3575 1775) $PN DJ56
J 2
(-3585 1785);
DISPLAY 0.680851 (-3585 1785);
PAINT MONO (-3585 1785);
FORCEPROP 0 LASTPIN (-3575 1825) $PN DJ60
J 2
(-3585 1835);
DISPLAY 0.680851 (-3585 1835);
PAINT MONO (-3585 1835);
FORCEPROP 0 LASTPIN (-3575 1925) $PN DJ66
J 2
(-3585 1935);
DISPLAY 0.680851 (-3585 1935);
PAINT MONO (-3585 1935);
FORCEPROP 0 LASTPIN (-3575 2025) $PN DJ72
J 2
(-3585 2035);
DISPLAY 0.680851 (-3585 2035);
PAINT MONO (-3585 2035);
FORCEPROP 0 LASTPIN (-3575 2075) $PN DJ74
J 2
(-3585 2085);
DISPLAY 0.680851 (-3585 2085);
PAINT MONO (-3585 2085);
FORCEPROP 0 LASTPIN (-3575 2125) $PN DJ80
J 2
(-3585 2135);
DISPLAY 0.680851 (-3585 2135);
PAINT MONO (-3585 2135);
FORCEPROP 0 LASTPIN (-3575 2175) $PN DJ82
J 2
(-3585 2185);
DISPLAY 0.680851 (-3585 2185);
PAINT MONO (-3585 2185);
FORCEPROP 0 LASTPIN (-3575 2225) $PN DJ84
J 2
(-3585 2235);
DISPLAY 0.680851 (-3585 2235);
PAINT MONO (-3585 2235);
FORCEPROP 0 LASTPIN (-3575 2275) $PN DJ88
J 2
(-3585 2285);
DISPLAY 0.680851 (-3585 2285);
PAINT MONO (-3585 2285);
FORCEPROP 0 LASTPIN (-3575 2475) $PN DK16
J 2
(-3585 2485);
DISPLAY 0.680851 (-3585 2485);
PAINT MONO (-3585 2485);
FORCEPROP 0 LASTPIN (-3575 2625) $PN DK30
J 2
(-3585 2635);
DISPLAY 0.680851 (-3585 2635);
PAINT MONO (-3585 2635);
FORCEPROP 0 LASTPIN (-3575 2675) $PN DK36
J 2
(-3585 2685);
DISPLAY 0.680851 (-3585 2685);
PAINT MONO (-3585 2685);
FORCEPROP 0 LASTPIN (-3575 2325) $PN DK4
J 2
(-3585 2335);
DISPLAY 0.680851 (-3585 2335);
PAINT MONO (-3585 2335);
FORCEPROP 0 LASTPIN (-3575 2775) $PN DK49
J 2
(-3585 2785);
DISPLAY 0.680851 (-3585 2785);
PAINT MONO (-3585 2785);
FORCEPROP 0 LASTPIN (-3575 2975) $PN DK73
J 2
(-3585 2985);
DISPLAY 0.680851 (-3585 2985);
PAINT MONO (-3585 2985);
FORCEPROP 0 LASTPIN (-3575 3025) $PN DK77
J 2
(-3585 3035);
DISPLAY 0.680851 (-3585 3035);
PAINT MONO (-3585 3035);
FORCEPROP 0 LASTPIN (-3575 3075) $PN DK79
J 2
(-3585 3085);
DISPLAY 0.680851 (-3585 3085);
PAINT MONO (-3585 3085);
FORCEPROP 0 LASTPIN (-3575 2375) $PN DK8
J 2
(-3585 2385);
DISPLAY 0.680851 (-3585 2385);
PAINT MONO (-3585 2385);
FORCEPROP 0 LASTPIN (-3575 3125) $PN DK81
J 2
(-3585 3135);
DISPLAY 0.680851 (-3585 3135);
PAINT MONO (-3585 3135);
FORCEPROP 0 LASTPIN (-3575 3175) $PN DK83
J 2
(-3585 3185);
DISPLAY 0.680851 (-3585 3185);
PAINT MONO (-3585 3185);
FORCEPROP 0 LASTPIN (-3575 3225) $PN DK87
J 2
(-3585 3235);
DISPLAY 0.680851 (-3585 3235);
PAINT MONO (-3585 3235);
FORCEPROP 0 LASTPIN (-3575 3275) $PN DK91
J 2
(-3585 3285);
DISPLAY 0.680851 (-3585 3285);
PAINT MONO (-3585 3285);
FORCEPROP 0 LASTPIN (-3575 3575) $PN DL39
J 2
(-3585 3585);
DISPLAY 0.680851 (-3585 3585);
PAINT MONO (-3585 3585);
FORCEPROP 0 LASTPIN (-3575 3675) $PN DL84
J 2
(-3585 3685);
DISPLAY 0.680851 (-3585 3685);
PAINT MONO (-3585 3685);
FORCEPROP 0 LASTPIN (-3575 3725) $PN DL88
J 2
(-3585 3735);
DISPLAY 0.680851 (-3585 3735);
PAINT MONO (-3585 3735);
FORCEPROP 0 LASTPIN (-3575 3425) $PN DL9
J 2
(-3585 3435);
DISPLAY 0.680851 (-3585 3435);
PAINT MONO (-3585 3435);
FORCEPROP 2 LAST CDS_LIB pure_quanta
J 0
(-2375 1750);
DISPLAY INVISIBLE (-2375 1750);
FORCEPROP 1 LAST NEEDS_NO_SIZE TRUE
J 0
(-2375 1750);
DISPLAY 0.723404 (-2375 1750);
PAINT GREEN (-2375 1750);
DISPLAY INVISIBLE (-2375 1750);
FORCEPROP 1 LAST CDS_LMAN_SYM_OUTLINE -1050,2150,1050,-2100
J 0
(-2375 1750);
DISPLAY 0.468085 (-2375 1750);
PAINT GREEN (-2375 1750);
DISPLAY INVISIBLE (-2375 1750);
FORCEPROP 0 LAST CDS_LOCATION U1
J 0
(-3425 4225);
DISPLAY 1.021277 (-3425 4225);
DISPLAY INVISIBLE (-3425 4225);
FORCEPROP 0 LAST $SEC 34
J 0
(-3425 4225);
DISPLAY 0.680851 (-3425 4225);
PAINT MONO (-3425 4225);
DISPLAY INVISIBLE (-3425 4225);
FORCEPROP 2 LAST CDS_SEC 34
J 0
(-3425 4225);
DISPLAY 1.021277 (-3425 4225);
DISPLAY INVISIBLE (-3425 4225);
FORCEPROP 1 LAST PATH I2
J 0
(-2375 1750);
DISPLAY 0.723404 (-2375 1750);
PAINT GREEN (-2375 1750);
DISPLAY INVISIBLE (-2375 1750);
FORCEADD UNIVERSAL_GND..1
(-925 -775);
FORCEPROP 3 LASTPIN (-925 -725) SIG_NAME GND\g
J 0
(-915 -715);
DISPLAY 0.659574 (-915 -715);
PAINT MONO (-915 -715);
DISPLAY INVISIBLE (-915 -715);
FORCEPROP 2 LAST CDS_LIB logical_power
J 0
(-925 -775);
PAINT MONO (-925 -775);
DISPLAY INVISIBLE (-925 -775);
FORCEPROP 1 LAST HDL_POWER GND
J 1
(-900 -850);
DISPLAY 0.872340 (-900 -850);
PAINT GREEN (-900 -850);
DISPLAY INVISIBLE (-900 -850);
FORCEPROP 1 LAST PATH I3
J 0
(-850 -775);
DISPLAY 0.872340 (-850 -775);
PAINT AQUA (-850 -775);
DISPLAY INVISIBLE (-850 -775);
FORCEADD UNIVERSAL_GND..1
(-775 -775);
FORCEPROP 3 LASTPIN (-775 -725) SIG_NAME GND\g
J 0
(-765 -715);
DISPLAY 0.659574 (-765 -715);
PAINT MONO (-765 -715);
DISPLAY INVISIBLE (-765 -715);
FORCEPROP 2 LAST CDS_LIB logical_power
J 0
(-775 -775);
PAINT MONO (-775 -775);
DISPLAY INVISIBLE (-775 -775);
FORCEPROP 1 LAST HDL_POWER GND
J 1
(-750 -850);
DISPLAY 0.872340 (-750 -850);
PAINT GREEN (-750 -850);
DISPLAY INVISIBLE (-750 -850);
FORCEPROP 1 LAST PATH I4
J 0
(-700 -775);
DISPLAY 0.872340 (-700 -775);
PAINT AQUA (-700 -775);
DISPLAY INVISIBLE (-700 -775);
FORCEADD SOCKET4677_AZIF0045P001C01CS..35
(675 1750);
FORCEPROP 1 LAST PART_NUMBER DGA^7000023
J 0
(-375 4000);
DISPLAY 0.723404 (-375 4000);
PAINT GREEN (-375 4000);
DISPLAY INVISIBLE (-375 4000);
FORCEPROP 2 LAST PART_TYPE SMLF
J 0
(-375 4175);
DISPLAY 1.021277 (-375 4175);
FORCEPROP 1 LAST MATERIAL IO
J 0
(-375 3925);
DISPLAY 0.723404 (-375 3925);
PAINT GREEN (-375 3925);
FORCEPROP 2 LAST VALUE SOCKET4677_AZIF0045-P001C01CS
J 0
(-375 4125);
DISPLAY 1.021277 (-375 4125);
FORCEPROP 1 LAST $LOCATION U1
J 0
(-375 4075);
DISPLAY 0.723404 (-375 4075);
PAINT GREEN (-375 4075);
FORCEPROP 0 LASTPIN (1875 575) $PN CM16
J 0
(1885 585);
DISPLAY 0.680851 (1885 585);
PAINT MONO (1885 585);
FORCEPROP 0 LASTPIN (1875 675) $PN CM22
J 0
(1885 685);
DISPLAY 0.680851 (1885 685);
PAINT MONO (1885 685);
FORCEPROP 0 LASTPIN (1875 1325) $PN CN76
J 0
(1885 1335);
DISPLAY 0.680851 (1885 1335);
PAINT MONO (1885 1335);
FORCEPROP 0 LASTPIN (1875 1625) $PN CP16
J 0
(1885 1635);
DISPLAY 0.680851 (1885 1635);
PAINT MONO (1885 1635);
FORCEPROP 0 LASTPIN (1875 1825) $PN CP79
J 0
(1885 1835);
DISPLAY 0.680851 (1885 1835);
PAINT MONO (1885 1835);
FORCEPROP 0 LASTPIN (1875 2425) $PN CR78
J 0
(1885 2435);
DISPLAY 0.680851 (1885 2435);
PAINT MONO (1885 2435);
FORCEPROP 0 LASTPIN (1875 2825) $PN CT16
J 0
(1885 2835);
DISPLAY 0.680851 (1885 2835);
PAINT MONO (1885 2835);
FORCEPROP 0 LASTPIN (1875 2625) $PN CT4
J 0
(1885 2635);
DISPLAY 0.680851 (1885 2635);
PAINT MONO (1885 2635);
FORCEPROP 0 LASTPIN (1875 2675) $PN CT8
J 0
(1885 2685);
DISPLAY 0.680851 (1885 2685);
PAINT MONO (1885 2685);
FORCEPROP 0 LASTPIN (1875 3025) $PN CT89
J 0
(1885 3035);
DISPLAY 0.680851 (1885 3035);
PAINT MONO (1885 3035);
FORCEPROP 0 LASTPIN (1875 3225) $PN CU25
J 0
(1885 3235);
DISPLAY 0.680851 (1885 3235);
PAINT MONO (1885 3235);
FORCEPROP 0 LASTPIN (1875 3425) $PN CU72
J 0
(1885 3435);
DISPLAY 0.680851 (1885 3435);
PAINT MONO (1885 3435);
FORCEPROP 0 LASTPIN (1875 3475) $PN CU78
J 0
(1885 3485);
DISPLAY 0.680851 (1885 3485);
PAINT MONO (1885 3485);
FORCEPROP 0 LASTPIN (-525 -225) $PN CV16
J 2
(-535 -215);
DISPLAY 0.680851 (-535 -215);
PAINT MONO (-535 -215);
FORCEPROP 0 LASTPIN (-525 -175) $PN CV26
J 2
(-535 -165);
DISPLAY 0.680851 (-535 -165);
PAINT MONO (-535 -165);
FORCEPROP 0 LASTPIN (-525 -75) $PN CV79
J 2
(-535 -65);
DISPLAY 0.680851 (-535 -65);
PAINT MONO (-535 -65);
FORCEPROP 0 LASTPIN (-525 375) $PN CW33
J 2
(-535 385);
DISPLAY 0.680851 (-535 385);
PAINT MONO (-535 385);
FORCEPROP 0 LASTPIN (-525 425) $PN CW70
J 2
(-535 435);
DISPLAY 0.680851 (-535 435);
PAINT MONO (-535 435);
FORCEPROP 0 LASTPIN (-525 675) $PN CY4
J 2
(-535 685);
DISPLAY 0.680851 (-535 685);
PAINT MONO (-535 685);
FORCEPROP 0 LASTPIN (-525 1725) $PN DA43
J 2
(-535 1735);
DISPLAY 0.680851 (-535 1735);
PAINT MONO (-535 1735);
FORCEPROP 0 LASTPIN (-525 2175) $PN DA68
J 2
(-535 2185);
DISPLAY 0.680851 (-535 2185);
PAINT MONO (-535 2185);
FORCEPROP 0 LASTPIN (-525 2675) $PN DB16
J 2
(-535 2685);
DISPLAY 0.680851 (-535 2685);
PAINT MONO (-535 2685);
FORCEPROP 0 LASTPIN (-525 2725) $PN DB20
J 2
(-535 2735);
DISPLAY 0.680851 (-535 2735);
PAINT MONO (-535 2735);
FORCEPROP 0 LASTPIN (-525 2825) $PN DB26
J 2
(-535 2835);
DISPLAY 0.680851 (-535 2835);
PAINT MONO (-535 2835);
FORCEPROP 0 LASTPIN (-525 2975) $PN DB34
J 2
(-535 2985);
DISPLAY 0.680851 (-535 2985);
PAINT MONO (-535 2985);
FORCEPROP 0 LASTPIN (-525 3125) $PN DB44
J 2
(-535 3135);
DISPLAY 0.680851 (-535 3135);
PAINT MONO (-535 3135);
FORCEPROP 0 LASTPIN (-525 3225) $PN DB51
J 2
(-535 3235);
DISPLAY 0.680851 (-535 3235);
PAINT MONO (-535 3235);
FORCEPROP 0 LASTPIN (-525 3275) $PN DB53
J 2
(-535 3285);
DISPLAY 0.680851 (-535 3285);
PAINT MONO (-535 3285);
FORCEPROP 0 LASTPIN (-525 3375) $PN DB59
J 2
(-535 3385);
DISPLAY 0.680851 (-535 3385);
PAINT MONO (-535 3385);
FORCEPROP 0 LASTPIN (-525 3425) $PN DB63
J 2
(-535 3435);
DISPLAY 0.680851 (-535 3435);
PAINT MONO (-535 3435);
FORCEPROP 0 LASTPIN (-525 3525) $PN DB69
J 2
(-535 3535);
DISPLAY 0.680851 (-535 3535);
PAINT MONO (-535 3535);
FORCEPROP 0 LASTPIN (-525 3625) $PN DB75
J 2
(-535 3635);
DISPLAY 0.680851 (-535 3635);
PAINT MONO (-535 3635);
FORCEPROP 0 LASTPIN (1875 -225) $PN CK63
J 0
(1885 -215);
DISPLAY 0.680851 (1885 -215);
PAINT MONO (1885 -215);
FORCEPROP 0 LASTPIN (1875 -175) $PN CK69
J 0
(1885 -165);
DISPLAY 0.680851 (1885 -165);
PAINT MONO (1885 -165);
FORCEPROP 0 LASTPIN (1875 -125) $PN CK81
J 0
(1885 -115);
DISPLAY 0.680851 (1885 -115);
PAINT MONO (1885 -115);
FORCEPROP 0 LASTPIN (1875 -75) $PN CL1
J 0
(1885 -65);
DISPLAY 0.680851 (1885 -65);
PAINT MONO (1885 -65);
FORCEPROP 0 LASTPIN (1875 75) $PN CL13
J 0
(1885 85);
DISPLAY 0.680851 (1885 85);
PAINT MONO (1885 85);
FORCEPROP 0 LASTPIN (1875 125) $PN CL17
J 0
(1885 135);
DISPLAY 0.680851 (1885 135);
PAINT MONO (1885 135);
FORCEPROP 0 LASTPIN (1875 -25) $PN CL5
J 0
(1885 -15);
DISPLAY 0.680851 (1885 -15);
PAINT MONO (1885 -15);
FORCEPROP 0 LASTPIN (1875 175) $PN CL62
J 0
(1885 185);
DISPLAY 0.680851 (1885 185);
PAINT MONO (1885 185);
FORCEPROP 0 LASTPIN (1875 225) $PN CL74
J 0
(1885 235);
DISPLAY 0.680851 (1885 235);
PAINT MONO (1885 235);
FORCEPROP 0 LASTPIN (1875 275) $PN CL78
J 0
(1885 285);
DISPLAY 0.680851 (1885 285);
PAINT MONO (1885 285);
FORCEPROP 0 LASTPIN (1875 325) $PN CL80
J 0
(1885 335);
DISPLAY 0.680851 (1885 335);
PAINT MONO (1885 335);
FORCEPROP 0 LASTPIN (1875 375) $PN CL82
J 0
(1885 385);
DISPLAY 0.680851 (1885 385);
PAINT MONO (1885 385);
FORCEPROP 0 LASTPIN (1875 25) $PN CL9
J 0
(1885 35);
DISPLAY 0.680851 (1885 35);
PAINT MONO (1885 35);
FORCEPROP 0 LASTPIN (1875 525) $PN CM12
J 0
(1885 535);
DISPLAY 0.680851 (1885 535);
PAINT MONO (1885 535);
FORCEPROP 0 LASTPIN (1875 625) $PN CM20
J 0
(1885 635);
DISPLAY 0.680851 (1885 635);
PAINT MONO (1885 635);
FORCEPROP 0 LASTPIN (1875 725) $PN CM24
J 0
(1885 735);
DISPLAY 0.680851 (1885 735);
PAINT MONO (1885 735);
FORCEPROP 0 LASTPIN (1875 425) $PN CM4
J 0
(1885 435);
DISPLAY 0.680851 (1885 435);
PAINT MONO (1885 435);
FORCEPROP 0 LASTPIN (1875 775) $PN CM61
J 0
(1885 785);
DISPLAY 0.680851 (1885 785);
PAINT MONO (1885 785);
FORCEPROP 0 LASTPIN (1875 825) $PN CM65
J 0
(1885 835);
DISPLAY 0.680851 (1885 835);
PAINT MONO (1885 835);
FORCEPROP 0 LASTPIN (1875 875) $PN CM67
J 0
(1885 885);
DISPLAY 0.680851 (1885 885);
PAINT MONO (1885 885);
FORCEPROP 0 LASTPIN (1875 925) $PN CM79
J 0
(1885 935);
DISPLAY 0.680851 (1885 935);
PAINT MONO (1885 935);
FORCEPROP 0 LASTPIN (1875 475) $PN CM8
J 0
(1885 485);
DISPLAY 0.680851 (1885 485);
PAINT MONO (1885 485);
FORCEPROP 0 LASTPIN (1875 975) $PN CM81
J 0
(1885 985);
DISPLAY 0.680851 (1885 985);
PAINT MONO (1885 985);
FORCEPROP 0 LASTPIN (1875 1025) $PN CM83
J 0
(1885 1035);
DISPLAY 0.680851 (1885 1035);
PAINT MONO (1885 1035);
FORCEPROP 0 LASTPIN (1875 1075) $PN CM85
J 0
(1885 1085);
DISPLAY 0.680851 (1885 1085);
PAINT MONO (1885 1085);
FORCEPROP 0 LASTPIN (1875 1125) $PN CN68
J 0
(1885 1135);
DISPLAY 0.680851 (1885 1135);
PAINT MONO (1885 1135);
FORCEPROP 0 LASTPIN (1875 1175) $PN CN70
J 0
(1885 1185);
DISPLAY 0.680851 (1885 1185);
PAINT MONO (1885 1185);
FORCEPROP 0 LASTPIN (1875 1225) $PN CN72
J 0
(1885 1235);
DISPLAY 0.680851 (1885 1235);
PAINT MONO (1885 1235);
FORCEPROP 0 LASTPIN (1875 1275) $PN CN74
J 0
(1885 1285);
DISPLAY 0.680851 (1885 1285);
PAINT MONO (1885 1285);
FORCEPROP 0 LASTPIN (1875 1375) $PN CN84
J 0
(1885 1385);
DISPLAY 0.680851 (1885 1385);
PAINT MONO (1885 1385);
FORCEPROP 0 LASTPIN (1875 1425) $PN CN86
J 0
(1885 1435);
DISPLAY 0.680851 (1885 1435);
PAINT MONO (1885 1435);
FORCEPROP 0 LASTPIN (1875 1575) $PN CP12
J 0
(1885 1585);
DISPLAY 0.680851 (1885 1585);
PAINT MONO (1885 1585);
FORCEPROP 0 LASTPIN (1875 1675) $PN CP18
J 0
(1885 1685);
DISPLAY 0.680851 (1885 1685);
PAINT MONO (1885 1685);
FORCEPROP 0 LASTPIN (1875 1475) $PN CP4
J 0
(1885 1485);
DISPLAY 0.680851 (1885 1485);
PAINT MONO (1885 1485);
FORCEPROP 0 LASTPIN (1875 1725) $PN CP75
J 0
(1885 1735);
DISPLAY 0.680851 (1885 1735);
PAINT MONO (1885 1735);
FORCEPROP 0 LASTPIN (1875 1775) $PN CP77
J 0
(1885 1785);
DISPLAY 0.680851 (1885 1785);
PAINT MONO (1885 1785);
FORCEPROP 0 LASTPIN (1875 1525) $PN CP8
J 0
(1885 1535);
DISPLAY 0.680851 (1885 1535);
PAINT MONO (1885 1535);
FORCEPROP 0 LASTPIN (1875 1875) $PN CP83
J 0
(1885 1885);
DISPLAY 0.680851 (1885 1885);
PAINT MONO (1885 1885);
FORCEPROP 0 LASTPIN (1875 1925) $PN CP87
J 0
(1885 1935);
DISPLAY 0.680851 (1885 1935);
PAINT MONO (1885 1935);
FORCEPROP 0 LASTPIN (1875 1975) $PN CP91
J 0
(1885 1985);
DISPLAY 0.680851 (1885 1985);
PAINT MONO (1885 1985);
FORCEPROP 0 LASTPIN (1875 2025) $PN CR1
J 0
(1885 2035);
DISPLAY 0.680851 (1885 2035);
PAINT MONO (1885 2035);
FORCEPROP 0 LASTPIN (1875 2175) $PN CR11
J 0
(1885 2185);
DISPLAY 0.680851 (1885 2185);
PAINT MONO (1885 2185);
FORCEPROP 0 LASTPIN (1875 2225) $PN CR13
J 0
(1885 2235);
DISPLAY 0.680851 (1885 2235);
PAINT MONO (1885 2235);
FORCEPROP 0 LASTPIN (1875 2275) $PN CR17
J 0
(1885 2285);
DISPLAY 0.680851 (1885 2285);
PAINT MONO (1885 2285);
FORCEPROP 0 LASTPIN (1875 2075) $PN CR5
J 0
(1885 2085);
DISPLAY 0.680851 (1885 2085);
PAINT MONO (1885 2085);
FORCEPROP 0 LASTPIN (1875 2325) $PN CR62
J 0
(1885 2335);
DISPLAY 0.680851 (1885 2335);
PAINT MONO (1885 2335);
FORCEPROP 0 LASTPIN (1875 2375) $PN CR64
J 0
(1885 2385);
DISPLAY 0.680851 (1885 2385);
PAINT MONO (1885 2385);
FORCEPROP 0 LASTPIN (1875 2475) $PN CR84
J 0
(1885 2485);
DISPLAY 0.680851 (1885 2485);
PAINT MONO (1885 2485);
FORCEPROP 0 LASTPIN (1875 2525) $PN CR88
J 0
(1885 2535);
DISPLAY 0.680851 (1885 2535);
PAINT MONO (1885 2535);
FORCEPROP 0 LASTPIN (1875 2125) $PN CR9
J 0
(1885 2135);
DISPLAY 0.680851 (1885 2135);
PAINT MONO (1885 2135);
FORCEPROP 0 LASTPIN (1875 2575) $PN CR90
J 0
(1885 2585);
DISPLAY 0.680851 (1885 2585);
PAINT MONO (1885 2585);
FORCEPROP 0 LASTPIN (1875 2725) $PN CT10
J 0
(1885 2735);
DISPLAY 0.680851 (1885 2735);
PAINT MONO (1885 2735);
FORCEPROP 0 LASTPIN (1875 2775) $PN CT12
J 0
(1885 2785);
DISPLAY 0.680851 (1885 2785);
PAINT MONO (1885 2785);
FORCEPROP 0 LASTPIN (1875 2875) $PN CT69
J 0
(1885 2885);
DISPLAY 0.680851 (1885 2885);
PAINT MONO (1885 2885);
FORCEPROP 0 LASTPIN (1875 2925) $PN CT73
J 0
(1885 2935);
DISPLAY 0.680851 (1885 2935);
PAINT MONO (1885 2935);
FORCEPROP 0 LASTPIN (1875 2975) $PN CT81
J 0
(1885 2985);
DISPLAY 0.680851 (1885 2985);
PAINT MONO (1885 2985);
FORCEPROP 0 LASTPIN (1875 3075) $PN CU19
J 0
(1885 3085);
DISPLAY 0.680851 (1885 3085);
PAINT MONO (1885 3085);
FORCEPROP 0 LASTPIN (1875 3125) $PN CU21
J 0
(1885 3135);
DISPLAY 0.680851 (1885 3135);
PAINT MONO (1885 3135);
FORCEPROP 0 LASTPIN (1875 3175) $PN CU23
J 0
(1885 3185);
DISPLAY 0.680851 (1885 3185);
PAINT MONO (1885 3185);
FORCEPROP 0 LASTPIN (1875 3275) $PN CU60
J 0
(1885 3285);
DISPLAY 0.680851 (1885 3285);
PAINT MONO (1885 3285);
FORCEPROP 0 LASTPIN (1875 3325) $PN CU66
J 0
(1885 3335);
DISPLAY 0.680851 (1885 3335);
PAINT MONO (1885 3335);
FORCEPROP 0 LASTPIN (1875 3375) $PN CU68
J 0
(1885 3385);
DISPLAY 0.680851 (1885 3385);
PAINT MONO (1885 3385);
FORCEPROP 0 LASTPIN (1875 3525) $PN CU84
J 0
(1885 3535);
DISPLAY 0.680851 (1885 3535);
PAINT MONO (1885 3535);
FORCEPROP 0 LASTPIN (1875 3575) $PN CU88
J 0
(1885 3585);
DISPLAY 0.680851 (1885 3585);
PAINT MONO (1885 3585);
FORCEPROP 0 LASTPIN (1875 3725) $PN CV12
J 0
(1885 3735);
DISPLAY 0.680851 (1885 3735);
PAINT MONO (1885 3735);
FORCEPROP 0 LASTPIN (1875 3625) $PN CV4
J 0
(1885 3635);
DISPLAY 0.680851 (1885 3635);
PAINT MONO (1885 3635);
FORCEPROP 0 LASTPIN (-525 -125) $PN CV75
J 2
(-535 -115);
DISPLAY 0.680851 (-535 -115);
PAINT MONO (-535 -115);
FORCEPROP 0 LASTPIN (1875 3675) $PN CV8
J 0
(1885 3685);
DISPLAY 0.680851 (1885 3685);
PAINT MONO (1885 3685);
FORCEPROP 0 LASTPIN (-525 -25) $PN CV83
J 2
(-535 -15);
DISPLAY 0.680851 (-535 -15);
PAINT MONO (-535 -15);
FORCEPROP 0 LASTPIN (-525 25) $PN CV87
J 2
(-535 35);
DISPLAY 0.680851 (-535 35);
PAINT MONO (-535 35);
FORCEPROP 0 LASTPIN (-525 75) $PN CV91
J 2
(-535 85);
DISPLAY 0.680851 (-535 85);
PAINT MONO (-535 85);
FORCEPROP 0 LASTPIN (-525 125) $PN CW1
J 2
(-535 135);
DISPLAY 0.680851 (-535 135);
PAINT MONO (-535 135);
FORCEPROP 0 LASTPIN (-525 275) $PN CW13
J 2
(-535 285);
DISPLAY 0.680851 (-535 285);
PAINT MONO (-535 285);
FORCEPROP 0 LASTPIN (-525 325) $PN CW17
J 2
(-535 335);
DISPLAY 0.680851 (-535 335);
PAINT MONO (-535 335);
FORCEPROP 0 LASTPIN (-525 175) $PN CW5
J 2
(-535 185);
DISPLAY 0.680851 (-535 185);
PAINT MONO (-535 185);
FORCEPROP 0 LASTPIN (-525 475) $PN CW72
J 2
(-535 485);
DISPLAY 0.680851 (-535 485);
PAINT MONO (-535 485);
FORCEPROP 0 LASTPIN (-525 525) $PN CW78
J 2
(-535 535);
DISPLAY 0.680851 (-535 535);
PAINT MONO (-535 535);
FORCEPROP 0 LASTPIN (-525 575) $PN CW84
J 2
(-535 585);
DISPLAY 0.680851 (-535 585);
PAINT MONO (-535 585);
FORCEPROP 0 LASTPIN (-525 625) $PN CW88
J 2
(-535 635);
DISPLAY 0.680851 (-535 635);
PAINT MONO (-535 635);
FORCEPROP 0 LASTPIN (-525 225) $PN CW9
J 2
(-535 235);
DISPLAY 0.680851 (-535 235);
PAINT MONO (-535 235);
FORCEPROP 0 LASTPIN (-525 775) $PN CY12
J 2
(-535 785);
DISPLAY 0.680851 (-535 785);
PAINT MONO (-535 785);
FORCEPROP 0 LASTPIN (-525 825) $PN CY16
J 2
(-535 835);
DISPLAY 0.680851 (-535 835);
PAINT MONO (-535 835);
FORCEPROP 0 LASTPIN (-525 875) $PN CY18
J 2
(-535 885);
DISPLAY 0.680851 (-535 885);
PAINT MONO (-535 885);
FORCEPROP 0 LASTPIN (-525 925) $PN CY26
J 2
(-535 935);
DISPLAY 0.680851 (-535 935);
PAINT MONO (-535 935);
FORCEPROP 0 LASTPIN (-525 975) $PN CY30
J 2
(-535 985);
DISPLAY 0.680851 (-535 985);
PAINT MONO (-535 985);
FORCEPROP 0 LASTPIN (-525 1025) $PN CY63
J 2
(-535 1035);
DISPLAY 0.680851 (-535 1035);
PAINT MONO (-535 1035);
FORCEPROP 0 LASTPIN (-525 1075) $PN CY73
J 2
(-535 1085);
DISPLAY 0.680851 (-535 1085);
PAINT MONO (-535 1085);
FORCEPROP 0 LASTPIN (-525 1125) $PN CY77
J 2
(-535 1135);
DISPLAY 0.680851 (-535 1135);
PAINT MONO (-535 1135);
FORCEPROP 0 LASTPIN (-525 725) $PN CY8
J 2
(-535 735);
DISPLAY 0.680851 (-535 735);
PAINT MONO (-535 735);
FORCEPROP 0 LASTPIN (-525 1175) $PN CY81
J 2
(-535 1185);
DISPLAY 0.680851 (-535 1185);
PAINT MONO (-535 1185);
FORCEPROP 0 LASTPIN (-525 1225) $PN CY83
J 2
(-535 1235);
DISPLAY 0.680851 (-535 1235);
PAINT MONO (-535 1235);
FORCEPROP 0 LASTPIN (-525 1275) $PN DA19
J 2
(-535 1285);
DISPLAY 0.680851 (-535 1285);
PAINT MONO (-535 1285);
FORCEPROP 0 LASTPIN (-525 1325) $PN DA23
J 2
(-535 1335);
DISPLAY 0.680851 (-535 1335);
PAINT MONO (-535 1335);
FORCEPROP 0 LASTPIN (-525 1375) $PN DA25
J 2
(-535 1385);
DISPLAY 0.680851 (-535 1385);
PAINT MONO (-535 1385);
FORCEPROP 0 LASTPIN (-525 1425) $PN DA29
J 2
(-535 1435);
DISPLAY 0.680851 (-535 1435);
PAINT MONO (-535 1435);
FORCEPROP 0 LASTPIN (-525 1475) $PN DA31
J 2
(-535 1485);
DISPLAY 0.680851 (-535 1485);
PAINT MONO (-535 1485);
FORCEPROP 0 LASTPIN (-525 1525) $PN DA33
J 2
(-535 1535);
DISPLAY 0.680851 (-535 1535);
PAINT MONO (-535 1535);
FORCEPROP 0 LASTPIN (-525 1575) $PN DA35
J 2
(-535 1585);
DISPLAY 0.680851 (-535 1585);
PAINT MONO (-535 1585);
FORCEPROP 0 LASTPIN (-525 1625) $PN DA37
J 2
(-535 1635);
DISPLAY 0.680851 (-535 1635);
PAINT MONO (-535 1635);
FORCEPROP 0 LASTPIN (-525 1675) $PN DA41
J 2
(-535 1685);
DISPLAY 0.680851 (-535 1685);
PAINT MONO (-535 1685);
FORCEPROP 0 LASTPIN (-525 1775) $PN DA48
J 2
(-535 1785);
DISPLAY 0.680851 (-535 1785);
PAINT MONO (-535 1785);
FORCEPROP 0 LASTPIN (-525 1825) $PN DA50
J 2
(-535 1835);
DISPLAY 0.680851 (-535 1835);
PAINT MONO (-535 1835);
FORCEPROP 0 LASTPIN (-525 1875) $PN DA54
J 2
(-535 1885);
DISPLAY 0.680851 (-535 1885);
PAINT MONO (-535 1885);
FORCEPROP 0 LASTPIN (-525 1925) $PN DA56
J 2
(-535 1935);
DISPLAY 0.680851 (-535 1935);
PAINT MONO (-535 1935);
FORCEPROP 0 LASTPIN (-525 1975) $PN DA58
J 2
(-535 1985);
DISPLAY 0.680851 (-535 1985);
PAINT MONO (-535 1985);
FORCEPROP 0 LASTPIN (-525 2025) $PN DA60
J 2
(-535 2035);
DISPLAY 0.680851 (-535 2035);
PAINT MONO (-535 2035);
FORCEPROP 0 LASTPIN (-525 2075) $PN DA62
J 2
(-535 2085);
DISPLAY 0.680851 (-535 2085);
PAINT MONO (-535 2085);
FORCEPROP 0 LASTPIN (-525 2125) $PN DA66
J 2
(-535 2135);
DISPLAY 0.680851 (-535 2135);
PAINT MONO (-535 2135);
FORCEPROP 0 LASTPIN (-525 2225) $PN DA72
J 2
(-535 2235);
DISPLAY 0.680851 (-535 2235);
PAINT MONO (-535 2235);
FORCEPROP 0 LASTPIN (-525 2275) $PN DA74
J 2
(-535 2285);
DISPLAY 0.680851 (-535 2285);
PAINT MONO (-535 2285);
FORCEPROP 0 LASTPIN (-525 2325) $PN DA80
J 2
(-535 2335);
DISPLAY 0.680851 (-535 2335);
PAINT MONO (-535 2335);
FORCEPROP 0 LASTPIN (-525 2375) $PN DA82
J 2
(-535 2385);
DISPLAY 0.680851 (-535 2385);
PAINT MONO (-535 2385);
FORCEPROP 0 LASTPIN (-525 2425) $PN DA84
J 2
(-535 2435);
DISPLAY 0.680851 (-535 2435);
PAINT MONO (-535 2435);
FORCEPROP 0 LASTPIN (-525 2475) $PN DA88
J 2
(-535 2485);
DISPLAY 0.680851 (-535 2485);
PAINT MONO (-535 2485);
FORCEPROP 0 LASTPIN (-525 2625) $PN DB12
J 2
(-535 2635);
DISPLAY 0.680851 (-535 2635);
PAINT MONO (-535 2635);
FORCEPROP 0 LASTPIN (-525 2775) $PN DB22
J 2
(-535 2785);
DISPLAY 0.680851 (-535 2785);
PAINT MONO (-535 2785);
FORCEPROP 0 LASTPIN (-525 2875) $PN DB28
J 2
(-535 2885);
DISPLAY 0.680851 (-535 2885);
PAINT MONO (-535 2885);
FORCEPROP 0 LASTPIN (-525 2925) $PN DB32
J 2
(-535 2935);
DISPLAY 0.680851 (-535 2935);
PAINT MONO (-535 2935);
FORCEPROP 0 LASTPIN (-525 3025) $PN DB38
J 2
(-535 3035);
DISPLAY 0.680851 (-535 3035);
PAINT MONO (-535 3035);
FORCEPROP 0 LASTPIN (-525 2525) $PN DB4
J 2
(-535 2535);
DISPLAY 0.680851 (-535 2535);
PAINT MONO (-535 2535);
FORCEPROP 0 LASTPIN (-525 3075) $PN DB40
J 2
(-535 3085);
DISPLAY 0.680851 (-535 3085);
PAINT MONO (-535 3085);
FORCEPROP 0 LASTPIN (-525 3175) $PN DB47
J 2
(-535 3185);
DISPLAY 0.680851 (-535 3185);
PAINT MONO (-535 3185);
FORCEPROP 0 LASTPIN (-525 3325) $PN DB57
J 2
(-535 3335);
DISPLAY 0.680851 (-535 3335);
PAINT MONO (-535 3335);
FORCEPROP 0 LASTPIN (-525 3475) $PN DB65
J 2
(-535 3485);
DISPLAY 0.680851 (-535 3485);
PAINT MONO (-535 3485);
FORCEPROP 0 LASTPIN (-525 3575) $PN DB71
J 2
(-535 3585);
DISPLAY 0.680851 (-535 3585);
PAINT MONO (-535 3585);
FORCEPROP 0 LASTPIN (-525 3675) $PN DB77
J 2
(-535 3685);
DISPLAY 0.680851 (-535 3685);
PAINT MONO (-535 3685);
FORCEPROP 0 LASTPIN (-525 2575) $PN DB8
J 2
(-535 2585);
DISPLAY 0.680851 (-535 2585);
PAINT MONO (-535 2585);
FORCEPROP 0 LASTPIN (-525 3725) $PN DB87
J 2
(-535 3735);
DISPLAY 0.680851 (-535 3735);
PAINT MONO (-535 3735);
FORCEPROP 2 LAST CDS_LIB pure_quanta
J 0
(675 1750);
DISPLAY INVISIBLE (675 1750);
FORCEPROP 1 LAST NEEDS_NO_SIZE TRUE
J 0
(675 1750);
DISPLAY 0.723404 (675 1750);
PAINT GREEN (675 1750);
DISPLAY INVISIBLE (675 1750);
FORCEPROP 1 LAST CDS_LMAN_SYM_OUTLINE -1050,2150,1050,-2100
J 0
(675 1750);
DISPLAY 0.468085 (675 1750);
PAINT GREEN (675 1750);
DISPLAY INVISIBLE (675 1750);
FORCEPROP 0 LAST CDS_LOCATION U1
J 0
(-375 4225);
DISPLAY 1.021277 (-375 4225);
DISPLAY INVISIBLE (-375 4225);
FORCEPROP 0 LAST $SEC 35
J 0
(-375 4225);
DISPLAY 0.680851 (-375 4225);
PAINT MONO (-375 4225);
DISPLAY INVISIBLE (-375 4225);
FORCEPROP 2 LAST CDS_SEC 35
J 0
(-375 4225);
DISPLAY 1.021277 (-375 4225);
DISPLAY INVISIBLE (-375 4225);
FORCEPROP 1 LAST PATH I5
J 0
(675 1750);
DISPLAY 0.723404 (675 1750);
PAINT GREEN (675 1750);
DISPLAY INVISIBLE (675 1750);
FORCEADD UNIVERSAL_GND..1
(2125 -775);
FORCEPROP 3 LASTPIN (2125 -725) SIG_NAME GND\g
J 0
(2135 -715);
DISPLAY 0.659574 (2135 -715);
PAINT MONO (2135 -715);
DISPLAY INVISIBLE (2135 -715);
FORCEPROP 2 LAST CDS_LIB logical_power
J 0
(2125 -775);
PAINT MONO (2125 -775);
DISPLAY INVISIBLE (2125 -775);
FORCEPROP 1 LAST HDL_POWER GND
J 1
(2150 -850);
DISPLAY 0.872340 (2150 -850);
PAINT GREEN (2150 -850);
DISPLAY INVISIBLE (2150 -850);
FORCEPROP 1 LAST PATH I6
J 0
(2200 -775);
DISPLAY 0.872340 (2200 -775);
PAINT AQUA (2200 -775);
DISPLAY INVISIBLE (2200 -775);
FORCEADD UNIVERSAL_GND..1
(2250 -775);
FORCEPROP 3 LASTPIN (2250 -725) SIG_NAME GND\g
J 0
(2260 -715);
DISPLAY 0.659574 (2260 -715);
PAINT MONO (2260 -715);
DISPLAY INVISIBLE (2260 -715);
FORCEPROP 2 LAST CDS_LIB logical_power
J 0
(2250 -775);
PAINT MONO (2250 -775);
DISPLAY INVISIBLE (2250 -775);
FORCEPROP 1 LAST HDL_POWER GND
J 1
(2275 -850);
DISPLAY 0.872340 (2275 -850);
PAINT GREEN (2275 -850);
DISPLAY INVISIBLE (2275 -850);
FORCEPROP 1 LAST PATH I7
J 0
(2325 -775);
DISPLAY 0.872340 (2325 -775);
PAINT AQUA (2325 -775);
DISPLAY INVISIBLE (2325 -775);
FORCEADD SOCKET4677_AZIF0045P001C01CS..36
(3700 1750);
FORCEPROP 1 LAST PART_NUMBER DGA^7000023
J 0
(2650 4000);
DISPLAY 0.723404 (2650 4000);
PAINT GREEN (2650 4000);
DISPLAY INVISIBLE (2650 4000);
FORCEPROP 2 LAST PART_TYPE SMLF
J 0
(2650 4175);
DISPLAY 1.021277 (2650 4175);
FORCEPROP 1 LAST MATERIAL IO
J 0
(2650 3925);
DISPLAY 0.723404 (2650 3925);
PAINT GREEN (2650 3925);
FORCEPROP 2 LAST VALUE SOCKET4677_AZIF0045-P001C01CS
J 0
(2650 4125);
DISPLAY 1.021277 (2650 4125);
FORCEPROP 1 LAST $LOCATION U1
J 0
(2650 4075);
DISPLAY 0.723404 (2650 4075);
PAINT GREEN (2650 4075);
FORCEPROP 0 LASTPIN (2500 3375) $PN CJ76
J 2
(2490 3385);
DISPLAY 0.680851 (2490 3385);
PAINT MONO (2490 3385);
FORCEPROP 0 LASTPIN (2500 3475) $PN CK4
J 2
(2490 3485);
DISPLAY 0.680851 (2490 3485);
PAINT MONO (2490 3485);
FORCEPROP 0 LASTPIN (4900 -225) $PN BR35
J 0
(4910 -215);
DISPLAY 0.680851 (4910 -215);
PAINT MONO (4910 -215);
FORCEPROP 0 LASTPIN (4900 -175) $PN BR37
J 0
(4910 -165);
DISPLAY 0.680851 (4910 -165);
PAINT MONO (4910 -165);
FORCEPROP 0 LASTPIN (4900 -125) $PN BR39
J 0
(4910 -115);
DISPLAY 0.680851 (4910 -115);
PAINT MONO (4910 -115);
FORCEPROP 0 LASTPIN (4900 -75) $PN BR41
J 0
(4910 -65);
DISPLAY 0.680851 (4910 -65);
PAINT MONO (4910 -65);
FORCEPROP 0 LASTPIN (4900 -25) $PN BR43
J 0
(4910 -15);
DISPLAY 0.680851 (4910 -15);
PAINT MONO (4910 -15);
FORCEPROP 0 LASTPIN (4900 25) $PN BR45
J 0
(4910 35);
DISPLAY 0.680851 (4910 35);
PAINT MONO (4910 35);
FORCEPROP 0 LASTPIN (4900 75) $PN BR48
J 0
(4910 85);
DISPLAY 0.680851 (4910 85);
PAINT MONO (4910 85);
FORCEPROP 0 LASTPIN (4900 125) $PN BR50
J 0
(4910 135);
DISPLAY 0.680851 (4910 135);
PAINT MONO (4910 135);
FORCEPROP 0 LASTPIN (4900 175) $PN BR52
J 0
(4910 185);
DISPLAY 0.680851 (4910 185);
PAINT MONO (4910 185);
FORCEPROP 0 LASTPIN (4900 225) $PN BR54
J 0
(4910 235);
DISPLAY 0.680851 (4910 235);
PAINT MONO (4910 235);
FORCEPROP 0 LASTPIN (4900 275) $PN BR56
J 0
(4910 285);
DISPLAY 0.680851 (4910 285);
PAINT MONO (4910 285);
FORCEPROP 0 LASTPIN (4900 325) $PN BR58
J 0
(4910 335);
DISPLAY 0.680851 (4910 335);
PAINT MONO (4910 335);
FORCEPROP 0 LASTPIN (4900 375) $PN BR64
J 0
(4910 385);
DISPLAY 0.680851 (4910 385);
PAINT MONO (4910 385);
FORCEPROP 0 LASTPIN (4900 425) $PN BR66
J 0
(4910 435);
DISPLAY 0.680851 (4910 435);
PAINT MONO (4910 435);
FORCEPROP 0 LASTPIN (4900 475) $PN BR68
J 0
(4910 485);
DISPLAY 0.680851 (4910 485);
PAINT MONO (4910 485);
FORCEPROP 0 LASTPIN (4900 525) $PN BR70
J 0
(4910 535);
DISPLAY 0.680851 (4910 535);
PAINT MONO (4910 535);
FORCEPROP 0 LASTPIN (4900 575) $PN BR72
J 0
(4910 585);
DISPLAY 0.680851 (4910 585);
PAINT MONO (4910 585);
FORCEPROP 0 LASTPIN (4900 625) $PN BR74
J 0
(4910 635);
DISPLAY 0.680851 (4910 635);
PAINT MONO (4910 635);
FORCEPROP 0 LASTPIN (4900 675) $PN BR76
J 0
(4910 685);
DISPLAY 0.680851 (4910 685);
PAINT MONO (4910 685);
FORCEPROP 0 LASTPIN (4900 725) $PN BR80
J 0
(4910 735);
DISPLAY 0.680851 (4910 735);
PAINT MONO (4910 735);
FORCEPROP 0 LASTPIN (4900 775) $PN BR82
J 0
(4910 785);
DISPLAY 0.680851 (4910 785);
PAINT MONO (4910 785);
FORCEPROP 0 LASTPIN (4900 825) $PN BR84
J 0
(4910 835);
DISPLAY 0.680851 (4910 835);
PAINT MONO (4910 835);
FORCEPROP 0 LASTPIN (4900 875) $PN BR86
J 0
(4910 885);
DISPLAY 0.680851 (4910 885);
PAINT MONO (4910 885);
FORCEPROP 0 LASTPIN (4900 925) $PN BR88
J 0
(4910 935);
DISPLAY 0.680851 (4910 935);
PAINT MONO (4910 935);
FORCEPROP 0 LASTPIN (4900 975) $PN BR90
J 0
(4910 985);
DISPLAY 0.680851 (4910 985);
PAINT MONO (4910 985);
FORCEPROP 0 LASTPIN (4900 1125) $PN BT12
J 0
(4910 1135);
DISPLAY 0.680851 (4910 1135);
PAINT MONO (4910 1135);
FORCEPROP 0 LASTPIN (4900 1175) $PN BT16
J 0
(4910 1185);
DISPLAY 0.680851 (4910 1185);
PAINT MONO (4910 1185);
FORCEPROP 0 LASTPIN (4900 1225) $PN BT20
J 0
(4910 1235);
DISPLAY 0.680851 (4910 1235);
PAINT MONO (4910 1235);
FORCEPROP 0 LASTPIN (4900 1025) $PN BT4
J 0
(4910 1035);
DISPLAY 0.680851 (4910 1035);
PAINT MONO (4910 1035);
FORCEPROP 0 LASTPIN (4900 1075) $PN BT8
J 0
(4910 1085);
DISPLAY 0.680851 (4910 1085);
PAINT MONO (4910 1085);
FORCEPROP 0 LASTPIN (4900 1325) $PN BU15
J 0
(4910 1335);
DISPLAY 0.680851 (4910 1335);
PAINT MONO (4910 1335);
FORCEPROP 0 LASTPIN (4900 1375) $PN BU19
J 0
(4910 1385);
DISPLAY 0.680851 (4910 1385);
PAINT MONO (4910 1385);
FORCEPROP 0 LASTPIN (4900 1425) $PN BU21
J 0
(4910 1435);
DISPLAY 0.680851 (4910 1435);
PAINT MONO (4910 1435);
FORCEPROP 0 LASTPIN (4900 1475) $PN BU23
J 0
(4910 1485);
DISPLAY 0.680851 (4910 1485);
PAINT MONO (4910 1485);
FORCEPROP 0 LASTPIN (4900 1525) $PN BU25
J 0
(4910 1535);
DISPLAY 0.680851 (4910 1535);
PAINT MONO (4910 1535);
FORCEPROP 0 LASTPIN (4900 1575) $PN BU31
J 0
(4910 1585);
DISPLAY 0.680851 (4910 1585);
PAINT MONO (4910 1585);
FORCEPROP 0 LASTPIN (4900 1275) $PN BU7
J 0
(4910 1285);
DISPLAY 0.680851 (4910 1285);
PAINT MONO (4910 1285);
FORCEPROP 0 LASTPIN (4900 1825) $PN BV12
J 0
(4910 1835);
DISPLAY 0.680851 (4910 1835);
PAINT MONO (4910 1835);
FORCEPROP 0 LASTPIN (4900 1875) $PN BV16
J 0
(4910 1885);
DISPLAY 0.680851 (4910 1885);
PAINT MONO (4910 1885);
FORCEPROP 0 LASTPIN (4900 1925) $PN BV18
J 0
(4910 1935);
DISPLAY 0.680851 (4910 1935);
PAINT MONO (4910 1935);
FORCEPROP 0 LASTPIN (4900 1625) $PN BV2
J 0
(4910 1635);
DISPLAY 0.680851 (4910 1635);
PAINT MONO (4910 1635);
FORCEPROP 0 LASTPIN (4900 1975) $PN BV20
J 0
(4910 1985);
DISPLAY 0.680851 (4910 1985);
PAINT MONO (4910 1985);
FORCEPROP 0 LASTPIN (4900 1675) $PN BV4
J 0
(4910 1685);
DISPLAY 0.680851 (4910 1685);
PAINT MONO (4910 1685);
FORCEPROP 0 LASTPIN (4900 1725) $PN BV6
J 0
(4910 1735);
DISPLAY 0.680851 (4910 1735);
PAINT MONO (4910 1735);
FORCEPROP 0 LASTPIN (4900 1775) $PN BV8
J 0
(4910 1785);
DISPLAY 0.680851 (4910 1785);
PAINT MONO (4910 1785);
FORCEPROP 0 LASTPIN (4900 2175) $PN BW13
J 0
(4910 2185);
DISPLAY 0.680851 (4910 2185);
PAINT MONO (4910 2185);
FORCEPROP 0 LASTPIN (4900 2225) $PN BW17
J 0
(4910 2235);
DISPLAY 0.680851 (4910 2235);
PAINT MONO (4910 2235);
FORCEPROP 0 LASTPIN (4900 2275) $PN BW27
J 0
(4910 2285);
DISPLAY 0.680851 (4910 2285);
PAINT MONO (4910 2285);
FORCEPROP 0 LASTPIN (4900 2325) $PN BW29
J 0
(4910 2335);
DISPLAY 0.680851 (4910 2335);
PAINT MONO (4910 2335);
FORCEPROP 0 LASTPIN (4900 2025) $PN BW3
J 0
(4910 2035);
DISPLAY 0.680851 (4910 2035);
PAINT MONO (4910 2035);
FORCEPROP 0 LASTPIN (4900 2375) $PN BW31
J 0
(4910 2385);
DISPLAY 0.680851 (4910 2385);
PAINT MONO (4910 2385);
FORCEPROP 0 LASTPIN (4900 2075) $PN BW5
J 0
(4910 2085);
DISPLAY 0.680851 (4910 2085);
PAINT MONO (4910 2085);
FORCEPROP 0 LASTPIN (4900 2125) $PN BW9
J 0
(4910 2135);
DISPLAY 0.680851 (4910 2135);
PAINT MONO (4910 2135);
FORCEPROP 0 LASTPIN (4900 2525) $PN BY12
J 0
(4910 2535);
DISPLAY 0.680851 (4910 2535);
PAINT MONO (4910 2535);
FORCEPROP 0 LASTPIN (4900 2575) $PN BY16
J 0
(4910 2585);
DISPLAY 0.680851 (4910 2585);
PAINT MONO (4910 2585);
FORCEPROP 0 LASTPIN (4900 2625) $PN BY20
J 0
(4910 2635);
DISPLAY 0.680851 (4910 2635);
PAINT MONO (4910 2635);
FORCEPROP 0 LASTPIN (4900 2425) $PN BY4
J 0
(4910 2435);
DISPLAY 0.680851 (4910 2435);
PAINT MONO (4910 2435);
FORCEPROP 0 LASTPIN (4900 2475) $PN BY8
J 0
(4910 2485);
DISPLAY 0.680851 (4910 2485);
PAINT MONO (4910 2485);
FORCEPROP 0 LASTPIN (4900 2675) $PN CA3
J 0
(4910 2685);
DISPLAY 0.680851 (4910 2685);
PAINT MONO (4910 2685);
FORCEPROP 0 LASTPIN (4900 2725) $PN CA31
J 0
(4910 2735);
DISPLAY 0.680851 (4910 2735);
PAINT MONO (4910 2735);
FORCEPROP 0 LASTPIN (4900 2875) $PN CB12
J 0
(4910 2885);
DISPLAY 0.680851 (4910 2885);
PAINT MONO (4910 2885);
FORCEPROP 0 LASTPIN (4900 2925) $PN CB16
J 0
(4910 2935);
DISPLAY 0.680851 (4910 2935);
PAINT MONO (4910 2935);
FORCEPROP 0 LASTPIN (4900 2975) $PN CB20
J 0
(4910 2985);
DISPLAY 0.680851 (4910 2985);
PAINT MONO (4910 2985);
FORCEPROP 0 LASTPIN (4900 3025) $PN CB22
J 0
(4910 3035);
DISPLAY 0.680851 (4910 3035);
PAINT MONO (4910 3035);
FORCEPROP 0 LASTPIN (4900 3075) $PN CB24
J 0
(4910 3085);
DISPLAY 0.680851 (4910 3085);
PAINT MONO (4910 3085);
FORCEPROP 0 LASTPIN (4900 3125) $PN CB26
J 0
(4910 3135);
DISPLAY 0.680851 (4910 3135);
PAINT MONO (4910 3135);
FORCEPROP 0 LASTPIN (4900 3175) $PN CB28
J 0
(4910 3185);
DISPLAY 0.680851 (4910 3185);
PAINT MONO (4910 3185);
FORCEPROP 0 LASTPIN (4900 3225) $PN CB32
J 0
(4910 3235);
DISPLAY 0.680851 (4910 3235);
PAINT MONO (4910 3235);
FORCEPROP 0 LASTPIN (4900 3275) $PN CB34
J 0
(4910 3285);
DISPLAY 0.680851 (4910 3285);
PAINT MONO (4910 3285);
FORCEPROP 0 LASTPIN (4900 3325) $PN CB36
J 0
(4910 3335);
DISPLAY 0.680851 (4910 3335);
PAINT MONO (4910 3335);
FORCEPROP 0 LASTPIN (4900 3375) $PN CB38
J 0
(4910 3385);
DISPLAY 0.680851 (4910 3385);
PAINT MONO (4910 3385);
FORCEPROP 0 LASTPIN (4900 2775) $PN CB4
J 0
(4910 2785);
DISPLAY 0.680851 (4910 2785);
PAINT MONO (4910 2785);
FORCEPROP 0 LASTPIN (4900 3425) $PN CB40
J 0
(4910 3435);
DISPLAY 0.680851 (4910 3435);
PAINT MONO (4910 3435);
FORCEPROP 0 LASTPIN (4900 3475) $PN CB42
J 0
(4910 3485);
DISPLAY 0.680851 (4910 3485);
PAINT MONO (4910 3485);
FORCEPROP 0 LASTPIN (4900 3525) $PN CB44
J 0
(4910 3535);
DISPLAY 0.680851 (4910 3535);
PAINT MONO (4910 3535);
FORCEPROP 0 LASTPIN (4900 3575) $PN CB47
J 0
(4910 3585);
DISPLAY 0.680851 (4910 3585);
PAINT MONO (4910 3585);
FORCEPROP 0 LASTPIN (4900 3625) $PN CB49
J 0
(4910 3635);
DISPLAY 0.680851 (4910 3635);
PAINT MONO (4910 3635);
FORCEPROP 0 LASTPIN (4900 3675) $PN CB51
J 0
(4910 3685);
DISPLAY 0.680851 (4910 3685);
PAINT MONO (4910 3685);
FORCEPROP 0 LASTPIN (4900 3725) $PN CB53
J 0
(4910 3735);
DISPLAY 0.680851 (4910 3735);
PAINT MONO (4910 3735);
FORCEPROP 0 LASTPIN (2500 -225) $PN CB55
J 2
(2490 -215);
DISPLAY 0.680851 (2490 -215);
PAINT MONO (2490 -215);
FORCEPROP 0 LASTPIN (2500 -175) $PN CB57
J 2
(2490 -165);
DISPLAY 0.680851 (2490 -165);
PAINT MONO (2490 -165);
FORCEPROP 0 LASTPIN (2500 -125) $PN CB59
J 2
(2490 -115);
DISPLAY 0.680851 (2490 -115);
PAINT MONO (2490 -115);
FORCEPROP 0 LASTPIN (2500 -75) $PN CB63
J 2
(2490 -65);
DISPLAY 0.680851 (2490 -65);
PAINT MONO (2490 -65);
FORCEPROP 0 LASTPIN (2500 -25) $PN CB65
J 2
(2490 -15);
DISPLAY 0.680851 (2490 -15);
PAINT MONO (2490 -15);
FORCEPROP 0 LASTPIN (2500 25) $PN CB67
J 2
(2490 35);
DISPLAY 0.680851 (2490 35);
PAINT MONO (2490 35);
FORCEPROP 0 LASTPIN (2500 75) $PN CB69
J 2
(2490 85);
DISPLAY 0.680851 (2490 85);
PAINT MONO (2490 85);
FORCEPROP 0 LASTPIN (2500 125) $PN CB71
J 2
(2490 135);
DISPLAY 0.680851 (2490 135);
PAINT MONO (2490 135);
FORCEPROP 0 LASTPIN (2500 175) $PN CB73
J 2
(2490 185);
DISPLAY 0.680851 (2490 185);
PAINT MONO (2490 185);
FORCEPROP 0 LASTPIN (2500 225) $PN CB79
J 2
(2490 235);
DISPLAY 0.680851 (2490 235);
PAINT MONO (2490 235);
FORCEPROP 0 LASTPIN (4900 2825) $PN CB8
J 0
(4910 2835);
DISPLAY 0.680851 (4910 2835);
PAINT MONO (4910 2835);
FORCEPROP 0 LASTPIN (2500 275) $PN CB81
J 2
(2490 285);
DISPLAY 0.680851 (2490 285);
PAINT MONO (2490 285);
FORCEPROP 0 LASTPIN (2500 325) $PN CB83
J 2
(2490 335);
DISPLAY 0.680851 (2490 335);
PAINT MONO (2490 335);
FORCEPROP 0 LASTPIN (2500 375) $PN CB85
J 2
(2490 385);
DISPLAY 0.680851 (2490 385);
PAINT MONO (2490 385);
FORCEPROP 0 LASTPIN (2500 425) $PN CB87
J 2
(2490 435);
DISPLAY 0.680851 (2490 435);
PAINT MONO (2490 435);
FORCEPROP 0 LASTPIN (2500 475) $PN CB89
J 2
(2490 485);
DISPLAY 0.680851 (2490 485);
PAINT MONO (2490 485);
FORCEPROP 0 LASTPIN (2500 625) $PN CC13
J 2
(2490 635);
DISPLAY 0.680851 (2490 635);
PAINT MONO (2490 635);
FORCEPROP 0 LASTPIN (2500 675) $PN CC17
J 2
(2490 685);
DISPLAY 0.680851 (2490 685);
PAINT MONO (2490 685);
FORCEPROP 0 LASTPIN (2500 725) $PN CC31
J 2
(2490 735);
DISPLAY 0.680851 (2490 735);
PAINT MONO (2490 735);
FORCEPROP 0 LASTPIN (2500 525) $PN CC5
J 2
(2490 535);
DISPLAY 0.680851 (2490 535);
PAINT MONO (2490 535);
FORCEPROP 0 LASTPIN (2500 775) $PN CC62
J 2
(2490 785);
DISPLAY 0.680851 (2490 785);
PAINT MONO (2490 785);
FORCEPROP 0 LASTPIN (2500 825) $PN CC70
J 2
(2490 835);
DISPLAY 0.680851 (2490 835);
PAINT MONO (2490 835);
FORCEPROP 0 LASTPIN (2500 875) $PN CC72
J 2
(2490 885);
DISPLAY 0.680851 (2490 885);
PAINT MONO (2490 885);
FORCEPROP 0 LASTPIN (2500 925) $PN CC74
J 2
(2490 935);
DISPLAY 0.680851 (2490 935);
PAINT MONO (2490 935);
FORCEPROP 0 LASTPIN (2500 575) $PN CC9
J 2
(2490 585);
DISPLAY 0.680851 (2490 585);
PAINT MONO (2490 585);
FORCEPROP 0 LASTPIN (2500 1075) $PN CD12
J 2
(2490 1085);
DISPLAY 0.680851 (2490 1085);
PAINT MONO (2490 1085);
FORCEPROP 0 LASTPIN (2500 1125) $PN CD16
J 2
(2490 1135);
DISPLAY 0.680851 (2490 1135);
PAINT MONO (2490 1135);
FORCEPROP 0 LASTPIN (2500 1175) $PN CD20
J 2
(2490 1185);
DISPLAY 0.680851 (2490 1185);
PAINT MONO (2490 1185);
FORCEPROP 0 LASTPIN (2500 975) $PN CD4
J 2
(2490 985);
DISPLAY 0.680851 (2490 985);
PAINT MONO (2490 985);
FORCEPROP 0 LASTPIN (2500 1225) $PN CD61
J 2
(2490 1235);
DISPLAY 0.680851 (2490 1235);
PAINT MONO (2490 1235);
FORCEPROP 0 LASTPIN (2500 1275) $PN CD75
J 2
(2490 1285);
DISPLAY 0.680851 (2490 1285);
PAINT MONO (2490 1285);
FORCEPROP 0 LASTPIN (2500 1325) $PN CD77
J 2
(2490 1335);
DISPLAY 0.680851 (2490 1335);
PAINT MONO (2490 1335);
FORCEPROP 0 LASTPIN (2500 1025) $PN CD8
J 2
(2490 1035);
DISPLAY 0.680851 (2490 1035);
PAINT MONO (2490 1035);
FORCEPROP 0 LASTPIN (2500 1375) $PN CE3
J 2
(2490 1385);
DISPLAY 0.680851 (2490 1385);
PAINT MONO (2490 1385);
FORCEPROP 0 LASTPIN (2500 1425) $PN CE60
J 2
(2490 1435);
DISPLAY 0.680851 (2490 1435);
PAINT MONO (2490 1435);
FORCEPROP 0 LASTPIN (2500 1475) $PN CE66
J 2
(2490 1485);
DISPLAY 0.680851 (2490 1485);
PAINT MONO (2490 1485);
FORCEPROP 0 LASTPIN (2500 1525) $PN CE72
J 2
(2490 1535);
DISPLAY 0.680851 (2490 1535);
PAINT MONO (2490 1535);
FORCEPROP 0 LASTPIN (2500 1575) $PN CE76
J 2
(2490 1585);
DISPLAY 0.680851 (2490 1585);
PAINT MONO (2490 1585);
FORCEPROP 0 LASTPIN (2500 1625) $PN CE78
J 2
(2490 1635);
DISPLAY 0.680851 (2490 1635);
PAINT MONO (2490 1635);
FORCEPROP 0 LASTPIN (2500 1775) $PN CF12
J 2
(2490 1785);
DISPLAY 0.680851 (2490 1785);
PAINT MONO (2490 1785);
FORCEPROP 0 LASTPIN (2500 1825) $PN CF16
J 2
(2490 1835);
DISPLAY 0.680851 (2490 1835);
PAINT MONO (2490 1835);
FORCEPROP 0 LASTPIN (2500 1875) $PN CF20
J 2
(2490 1885);
DISPLAY 0.680851 (2490 1885);
PAINT MONO (2490 1885);
FORCEPROP 0 LASTPIN (2500 1675) $PN CF4
J 2
(2490 1685);
DISPLAY 0.680851 (2490 1685);
PAINT MONO (2490 1685);
FORCEPROP 0 LASTPIN (2500 1925) $PN CF69
J 2
(2490 1935);
DISPLAY 0.680851 (2490 1935);
PAINT MONO (2490 1935);
FORCEPROP 0 LASTPIN (2500 1975) $PN CF71
J 2
(2490 1985);
DISPLAY 0.680851 (2490 1985);
PAINT MONO (2490 1985);
FORCEPROP 0 LASTPIN (2500 1725) $PN CF8
J 2
(2490 1735);
DISPLAY 0.680851 (2490 1735);
PAINT MONO (2490 1735);
FORCEPROP 0 LASTPIN (2500 2025) $PN CG1
J 2
(2490 2035);
DISPLAY 0.680851 (2490 2035);
PAINT MONO (2490 2035);
FORCEPROP 0 LASTPIN (2500 2175) $PN CG13
J 2
(2490 2185);
DISPLAY 0.680851 (2490 2185);
PAINT MONO (2490 2185);
FORCEPROP 0 LASTPIN (2500 2225) $PN CG17
J 2
(2490 2235);
DISPLAY 0.680851 (2490 2235);
PAINT MONO (2490 2235);
FORCEPROP 0 LASTPIN (2500 2275) $PN CG21
J 2
(2490 2285);
DISPLAY 0.680851 (2490 2285);
PAINT MONO (2490 2285);
FORCEPROP 0 LASTPIN (2500 2325) $PN CG23
J 2
(2490 2335);
DISPLAY 0.680851 (2490 2335);
PAINT MONO (2490 2335);
FORCEPROP 0 LASTPIN (2500 2375) $PN CG25
J 2
(2490 2385);
DISPLAY 0.680851 (2490 2385);
PAINT MONO (2490 2385);
FORCEPROP 0 LASTPIN (2500 2075) $PN CG5
J 2
(2490 2085);
DISPLAY 0.680851 (2490 2085);
PAINT MONO (2490 2085);
FORCEPROP 0 LASTPIN (2500 2425) $PN CG62
J 2
(2490 2435);
DISPLAY 0.680851 (2490 2435);
PAINT MONO (2490 2435);
FORCEPROP 0 LASTPIN (2500 2475) $PN CG64
J 2
(2490 2485);
DISPLAY 0.680851 (2490 2485);
PAINT MONO (2490 2485);
FORCEPROP 0 LASTPIN (2500 2525) $PN CG70
J 2
(2490 2535);
DISPLAY 0.680851 (2490 2535);
PAINT MONO (2490 2535);
FORCEPROP 0 LASTPIN (2500 2575) $PN CG72
J 2
(2490 2585);
DISPLAY 0.680851 (2490 2585);
PAINT MONO (2490 2585);
FORCEPROP 0 LASTPIN (2500 2625) $PN CG74
J 2
(2490 2635);
DISPLAY 0.680851 (2490 2635);
PAINT MONO (2490 2635);
FORCEPROP 0 LASTPIN (2500 2675) $PN CG78
J 2
(2490 2685);
DISPLAY 0.680851 (2490 2685);
PAINT MONO (2490 2685);
FORCEPROP 0 LASTPIN (2500 2125) $PN CG9
J 2
(2490 2135);
DISPLAY 0.680851 (2490 2135);
PAINT MONO (2490 2135);
FORCEPROP 0 LASTPIN (2500 2825) $PN CH12
J 2
(2490 2835);
DISPLAY 0.680851 (2490 2835);
PAINT MONO (2490 2835);
FORCEPROP 0 LASTPIN (2500 2875) $PN CH16
J 2
(2490 2885);
DISPLAY 0.680851 (2490 2885);
PAINT MONO (2490 2885);
FORCEPROP 0 LASTPIN (2500 2925) $PN CH20
J 2
(2490 2935);
DISPLAY 0.680851 (2490 2935);
PAINT MONO (2490 2935);
FORCEPROP 0 LASTPIN (2500 2725) $PN CH4
J 2
(2490 2735);
DISPLAY 0.680851 (2490 2735);
PAINT MONO (2490 2735);
FORCEPROP 0 LASTPIN (2500 2975) $PN CH67
J 2
(2490 2985);
DISPLAY 0.680851 (2490 2985);
PAINT MONO (2490 2985);
FORCEPROP 0 LASTPIN (2500 3025) $PN CH73
J 2
(2490 3035);
DISPLAY 0.680851 (2490 3035);
PAINT MONO (2490 3035);
FORCEPROP 0 LASTPIN (2500 3075) $PN CH79
J 2
(2490 3085);
DISPLAY 0.680851 (2490 3085);
PAINT MONO (2490 3085);
FORCEPROP 0 LASTPIN (2500 2775) $PN CH8
J 2
(2490 2785);
DISPLAY 0.680851 (2490 2785);
PAINT MONO (2490 2785);
FORCEPROP 0 LASTPIN (2500 3125) $PN CH83
J 2
(2490 3135);
DISPLAY 0.680851 (2490 3135);
PAINT MONO (2490 3135);
FORCEPROP 0 LASTPIN (2500 3175) $PN CH85
J 2
(2490 3185);
DISPLAY 0.680851 (2490 3185);
PAINT MONO (2490 3185);
FORCEPROP 0 LASTPIN (2500 3225) $PN CH87
J 2
(2490 3235);
DISPLAY 0.680851 (2490 3235);
PAINT MONO (2490 3235);
FORCEPROP 0 LASTPIN (2500 3275) $PN CH89
J 2
(2490 3285);
DISPLAY 0.680851 (2490 3285);
PAINT MONO (2490 3285);
FORCEPROP 0 LASTPIN (2500 3325) $PN CJ60
J 2
(2490 3335);
DISPLAY 0.680851 (2490 3335);
PAINT MONO (2490 3335);
FORCEPROP 0 LASTPIN (2500 3425) $PN CJ80
J 2
(2490 3435);
DISPLAY 0.680851 (2490 3435);
PAINT MONO (2490 3435);
FORCEPROP 0 LASTPIN (2500 3575) $PN CK12
J 2
(2490 3585);
DISPLAY 0.680851 (2490 3585);
PAINT MONO (2490 3585);
FORCEPROP 0 LASTPIN (2500 3625) $PN CK16
J 2
(2490 3635);
DISPLAY 0.680851 (2490 3635);
PAINT MONO (2490 3635);
FORCEPROP 0 LASTPIN (2500 3675) $PN CK20
J 2
(2490 3685);
DISPLAY 0.680851 (2490 3685);
PAINT MONO (2490 3685);
FORCEPROP 0 LASTPIN (2500 3725) $PN CK26
J 2
(2490 3735);
DISPLAY 0.680851 (2490 3735);
PAINT MONO (2490 3735);
FORCEPROP 0 LASTPIN (2500 3525) $PN CK8
J 2
(2490 3535);
DISPLAY 0.680851 (2490 3535);
PAINT MONO (2490 3535);
FORCEPROP 2 LAST CDS_LIB pure_quanta
J 0
(3700 1750);
DISPLAY INVISIBLE (3700 1750);
FORCEPROP 1 LAST NEEDS_NO_SIZE TRUE
J 0
(3700 1750);
DISPLAY 0.723404 (3700 1750);
PAINT GREEN (3700 1750);
DISPLAY INVISIBLE (3700 1750);
FORCEPROP 1 LAST CDS_LMAN_SYM_OUTLINE -1050,2150,1050,-2100
J 0
(3700 1750);
DISPLAY 0.468085 (3700 1750);
PAINT GREEN (3700 1750);
DISPLAY INVISIBLE (3700 1750);
FORCEPROP 0 LAST CDS_LOCATION U1
J 0
(2650 4225);
DISPLAY 1.021277 (2650 4225);
DISPLAY INVISIBLE (2650 4225);
FORCEPROP 0 LAST $SEC 36
J 0
(2650 4225);
DISPLAY 0.680851 (2650 4225);
PAINT MONO (2650 4225);
DISPLAY INVISIBLE (2650 4225);
FORCEPROP 2 LAST CDS_SEC 36
J 0
(2650 4225);
DISPLAY 1.021277 (2650 4225);
DISPLAY INVISIBLE (2650 4225);
FORCEPROP 1 LAST PATH I8
J 0
(3700 1750);
DISPLAY 0.723404 (3700 1750);
PAINT GREEN (3700 1750);
DISPLAY INVISIBLE (3700 1750);
FORCEADD UNIVERSAL_GND..1
(5150 -775);
FORCEPROP 3 LASTPIN (5150 -725) SIG_NAME GND\g
J 0
(5160 -715);
DISPLAY 0.659574 (5160 -715);
PAINT MONO (5160 -715);
DISPLAY INVISIBLE (5160 -715);
FORCEPROP 2 LAST CDS_LIB logical_power
J 0
(5150 -775);
PAINT MONO (5150 -775);
DISPLAY INVISIBLE (5150 -775);
FORCEPROP 1 LAST HDL_POWER GND
J 1
(5175 -850);
DISPLAY 0.872340 (5175 -850);
PAINT GREEN (5175 -850);
DISPLAY INVISIBLE (5175 -850);
FORCEPROP 1 LAST PATH I9
J 0
(5225 -775);
DISPLAY 0.872340 (5225 -775);
PAINT AQUA (5225 -775);
DISPLAY INVISIBLE (5225 -775);
FORCEADD QUANTA_TITLE_BLOCK_C..1
(5350 -1625);
FORCEPROP 0 LAST CDS_CON_LAST_MODIFIED Fri Aug 25 14:00:52 2023
J 0
(3465 -1610);
PAINT MONO (3465 -1610);
DISPLAY INVISIBLE (3465 -1610);
FORCEPROP 1 LAST CUSTOM_TXT_CDS <CON_LAST_MODIFIED>
J 0
(3465 -1610);
DISPLAY 0.978723 (3465 -1610);
FORCEPROP 2 LAST CUSTOM_TXT_CDS <XR_PAGE_TITLE>
J 0
(-2540 3625);
DISPLAY 0.638298 (-2540 3625);
PAINT PINK (-2540 3625);
DISPLAY INVISIBLE (-2540 3625);
FORCEPROP 2 LAST CUSTOM_TXT_CDS <Q_NUMBER>
J 0
(3947 -1522);
DISPLAY 1.212766 (3947 -1522);
FORCEPROP 1 LAST CUSTOM_TXT_CDS <NAME_2>
J 0
(2175 -1575);
FORCEPROP 1 LAST CUSTOM_TXT_CDS <NAME_1>
J 0
(2175 -1450);
FORCEPROP 1 LAST CUSTOM_TXT_CDS <Q_PROJ>
J 0
(2968 -1523);
DISPLAY 1.212766 (2968 -1523);
FORCEPROP 1 LAST CUSTOM_TXT_CDS <Q_REV>
J 0
(5166 -1522);
DISPLAY 1.212766 (5166 -1522);
FORCEPROP 1 LAST CUSTOM_TXT_CDS <CON_PAGE_NUM> OF <CON_TOTAL_PAGES>
J 0
(4904 -1607);
DISPLAY 0.978723 (4904 -1607);
FORCEPROP 1 LAST Q_TITLE SPR CPU1 POWER - GND (28 OF 30)
J 0
(-4016 -1599);
DISPLAY 1.957447 (-4016 -1599);
PAINT GREEN (-4016 -1599);
FORCEPROP 1 LAST Q_DEPT 
J 1
(1587 -1576);
DISPLAY 1.957447 (1587 -1576);
PAINT GREEN (1587 -1576);
FORCEPROP 1 LAST COMMENT_BODY TRUE
J 0
(5362 -1638);
DISPLAY 0.978723 (5362 -1638);
PAINT GREEN (5362 -1638);
DISPLAY INVISIBLE (5362 -1638);
FORCEPROP 2 LAST CDS_XR_PAGE_TITLE CR-71 : @S9S_MB_2U_LIB.S9S_MB_2U(SCH_1):PAGE71
J 0
(-2540 3625);
DISPLAY 0.638298 (-2540 3625);
PAINT PINK (-2540 3625);
DISPLAY INVISIBLE (-2540 3625);
FORCEPROP 2 LAST CDS_LIB pure_quanta
J 0
(5350 -1625);
PAINT MONO (5350 -1625);
DISPLAY INVISIBLE (5350 -1625);
FORCEPROP 1 LAST CDS_LMAN_SYM_OUTLINE -9475,6775,100,-125
J 0
(5350 -1625);
DISPLAY 0.468085 (5350 -1625);
PAINT GREEN (5350 -1625);
DISPLAY INVISIBLE (5350 -1625);
FORCEPROP 2 LAST PAGE_BORDER TRUE
J 0
(-2540 3625);
DISPLAY 0.638298 (-2540 3625);
PAINT PINK (-2540 3625);
DISPLAY INVISIBLE (-2540 3625);
WIRE 16 -1 (5150 -225)(5150 -725);
WIRE 16 -1 (5150 -175)(5150 -225);
WIRE 16 -1 (4900 -225)(5150 -225);
WIRE 16 -1 (2250 -225)(2250 -725);
WIRE 16 -1 (2250 -175)(2250 -225);
WIRE 16 -1 (2250 -225)(2500 -225);
WIRE 16 -1 (2125 -225)(2125 -725);
WIRE 16 -1 (2125 -175)(2125 -225);
WIRE 16 -1 (1875 -225)(2125 -225);
WIRE 16 -1 (-775 -225)(-775 -725);
WIRE 16 -1 (-775 -175)(-775 -225);
WIRE 16 -1 (-775 -225)(-525 -225);
WIRE 16 -1 (-925 -225)(-925 -725);
WIRE 16 -1 (-925 -175)(-925 -225);
WIRE 16 -1 (-1175 -225)(-925 -225);
WIRE 16 -1 (-3825 -225)(-3825 -725);
WIRE 16 -1 (-3825 -175)(-3825 -225);
WIRE 16 -1 (-3825 -225)(-3575 -225);
WIRE 16 -1 (-3575 3725)(-3825 3725);
WIRE 16 -1 (-3825 3725)(-3825 3675);
WIRE 16 -1 (-3575 3675)(-3825 3675);
WIRE 16 -1 (-3825 3675)(-3825 3625);
WIRE 16 -1 (-3575 3625)(-3825 3625);
WIRE 16 -1 (-3825 3625)(-3825 3575);
WIRE 16 -1 (-3575 3575)(-3825 3575);
WIRE 16 -1 (-3825 3575)(-3825 3525);
WIRE 16 -1 (-3575 3525)(-3825 3525);
WIRE 16 -1 (-3825 3525)(-3825 3475);
WIRE 16 -1 (-3575 3475)(-3825 3475);
WIRE 16 -1 (-3825 3475)(-3825 3425);
WIRE 16 -1 (-3575 3425)(-3825 3425);
WIRE 16 -1 (-3825 3425)(-3825 3375);
WIRE 16 -1 (-3575 3375)(-3825 3375);
WIRE 16 -1 (-3825 3375)(-3825 3325);
WIRE 16 -1 (-3575 3325)(-3825 3325);
WIRE 16 -1 (-3825 3325)(-3825 3275);
WIRE 16 -1 (-3575 3275)(-3825 3275);
WIRE 16 -1 (-3825 3275)(-3825 3225);
WIRE 16 -1 (-3575 3225)(-3825 3225);
WIRE 16 -1 (-3825 3225)(-3825 3175);
WIRE 16 -1 (-3575 3175)(-3825 3175);
WIRE 16 -1 (-3825 3175)(-3825 3125);
WIRE 16 -1 (-3575 3125)(-3825 3125);
WIRE 16 -1 (-3825 3125)(-3825 3075);
WIRE 16 -1 (-3575 3075)(-3825 3075);
WIRE 16 -1 (-3825 3025)(-3575 3025);
WIRE 16 -1 (-3825 3075)(-3825 3025);
WIRE 16 -1 (-3825 3025)(-3825 2975);
WIRE 16 -1 (-3825 2975)(-3575 2975);
WIRE 16 -1 (-3825 2975)(-3825 2925);
WIRE 16 -1 (-3825 2925)(-3575 2925);
WIRE 16 -1 (-3825 2925)(-3825 2875);
WIRE 16 -1 (-3825 2875)(-3575 2875);
WIRE 16 -1 (-3825 2875)(-3825 2825);
WIRE 16 -1 (-3825 2825)(-3575 2825);
WIRE 16 -1 (-3825 2825)(-3825 2775);
WIRE 16 -1 (-3825 2775)(-3575 2775);
WIRE 16 -1 (-3825 2775)(-3825 2725);
WIRE 16 -1 (-3825 2725)(-3575 2725);
WIRE 16 -1 (-3825 2725)(-3825 2675);
WIRE 16 -1 (-3825 2675)(-3575 2675);
WIRE 16 -1 (-3825 2675)(-3825 2625);
WIRE 16 -1 (-3825 2625)(-3575 2625);
WIRE 16 -1 (-3825 2625)(-3825 2575);
WIRE 16 -1 (-3825 2575)(-3575 2575);
WIRE 16 -1 (-3825 2575)(-3825 2525);
WIRE 16 -1 (-3825 2525)(-3575 2525);
WIRE 16 -1 (-3825 2525)(-3825 2475);
WIRE 16 -1 (-3825 2475)(-3575 2475);
WIRE 16 -1 (-3825 2475)(-3825 2425);
WIRE 16 -1 (-3825 2425)(-3575 2425);
WIRE 16 -1 (-3825 2425)(-3825 2375);
WIRE 16 -1 (-3825 2375)(-3575 2375);
WIRE 16 -1 (-3825 2375)(-3825 2325);
WIRE 16 -1 (-3825 2325)(-3575 2325);
WIRE 16 -1 (-3825 2325)(-3825 2275);
WIRE 16 -1 (-3825 2275)(-3575 2275);
WIRE 16 -1 (-3825 2275)(-3825 2225);
WIRE 16 -1 (-3825 2225)(-3575 2225);
WIRE 16 -1 (-3825 2225)(-3825 2175);
WIRE 16 -1 (-3825 2175)(-3575 2175);
WIRE 16 -1 (-3825 2175)(-3825 2125);
WIRE 16 -1 (-3825 2125)(-3575 2125);
WIRE 16 -1 (-3825 2125)(-3825 2075);
WIRE 16 -1 (-3825 2075)(-3575 2075);
WIRE 16 -1 (-3825 2025)(-3575 2025);
WIRE 16 -1 (-3825 2075)(-3825 2025);
WIRE 16 -1 (-3825 2025)(-3825 1975);
WIRE 16 -1 (-3825 1975)(-3575 1975);
WIRE 16 -1 (-3825 1975)(-3825 1925);
WIRE 16 -1 (-3825 1925)(-3575 1925);
WIRE 16 -1 (-3825 1925)(-3825 1875);
WIRE 16 -1 (-3825 1875)(-3575 1875);
WIRE 16 -1 (-3825 1875)(-3825 1825);
WIRE 16 -1 (-3825 1825)(-3575 1825);
WIRE 16 -1 (-3825 1825)(-3825 1775);
WIRE 16 -1 (-3825 1775)(-3575 1775);
WIRE 16 -1 (-3825 1775)(-3825 1725);
WIRE 16 -1 (-3825 1725)(-3575 1725);
WIRE 16 -1 (-3825 1725)(-3825 1675);
WIRE 16 -1 (-3575 1675)(-3825 1675);
WIRE 16 -1 (-3825 1675)(-3825 1625);
WIRE 16 -1 (-3825 1625)(-3575 1625);
WIRE 16 -1 (-3825 1625)(-3825 1575);
WIRE 16 -1 (-3825 1575)(-3575 1575);
WIRE 16 -1 (-3825 1575)(-3825 1525);
WIRE 16 -1 (-3825 1525)(-3575 1525);
WIRE 16 -1 (-3825 1525)(-3825 1475);
WIRE 16 -1 (-3825 1475)(-3575 1475);
WIRE 16 -1 (-3825 1475)(-3825 1425);
WIRE 16 -1 (-3825 1425)(-3575 1425);
WIRE 16 -1 (-3825 1425)(-3825 1375);
WIRE 16 -1 (-3825 1375)(-3575 1375);
WIRE 16 -1 (-3825 1375)(-3825 1325);
WIRE 16 -1 (-3825 1325)(-3575 1325);
WIRE 16 -1 (-3825 1325)(-3825 1275);
WIRE 16 -1 (-3825 1275)(-3575 1275);
WIRE 16 -1 (-3825 1275)(-3825 1225);
WIRE 16 -1 (-3825 1225)(-3575 1225);
WIRE 16 -1 (-3825 1225)(-3825 1175);
WIRE 16 -1 (-3825 1175)(-3575 1175);
WIRE 16 -1 (-3825 1175)(-3825 1125);
WIRE 16 -1 (-3825 1125)(-3575 1125);
WIRE 16 -1 (-3825 1125)(-3825 1075);
WIRE 16 -1 (-3825 1075)(-3575 1075);
WIRE 16 -1 (-3825 1075)(-3825 1025);
WIRE 16 -1 (-3825 1025)(-3575 1025);
WIRE 16 -1 (-3825 975)(-3575 975);
WIRE 16 -1 (-3825 1025)(-3825 975);
WIRE 16 -1 (-3825 975)(-3825 925);
WIRE 16 -1 (-3825 925)(-3575 925);
WIRE 16 -1 (-3825 925)(-3825 875);
WIRE 16 -1 (-3825 875)(-3575 875);
WIRE 16 -1 (-3825 875)(-3825 825);
WIRE 16 -1 (-3825 825)(-3575 825);
WIRE 16 -1 (-3825 825)(-3825 775);
WIRE 16 -1 (-3825 775)(-3575 775);
WIRE 16 -1 (-3825 775)(-3825 725);
WIRE 16 -1 (-3825 725)(-3575 725);
WIRE 16 -1 (-3825 725)(-3825 675);
WIRE 16 -1 (-3575 675)(-3825 675);
WIRE 16 -1 (-3825 675)(-3825 625);
WIRE 16 -1 (-3825 625)(-3575 625);
WIRE 16 -1 (-3825 625)(-3825 575);
WIRE 16 -1 (-3825 575)(-3575 575);
WIRE 16 -1 (-3825 575)(-3825 525);
WIRE 16 -1 (-3825 525)(-3575 525);
WIRE 16 -1 (-3825 525)(-3825 475);
WIRE 16 -1 (-3825 475)(-3575 475);
WIRE 16 -1 (-3825 475)(-3825 425);
WIRE 16 -1 (-3825 425)(-3575 425);
WIRE 16 -1 (-3825 425)(-3825 375);
WIRE 16 -1 (-3575 375)(-3825 375);
WIRE 16 -1 (-3825 375)(-3825 325);
WIRE 16 -1 (-3825 325)(-3575 325);
WIRE 16 -1 (-3825 325)(-3825 275);
WIRE 16 -1 (-3825 275)(-3575 275);
WIRE 16 -1 (-3825 275)(-3825 225);
WIRE 16 -1 (-3825 225)(-3575 225);
WIRE 16 -1 (-3825 225)(-3825 175);
WIRE 16 -1 (-3825 175)(-3575 175);
WIRE 16 -1 (-3825 175)(-3825 125);
WIRE 16 -1 (-3825 125)(-3575 125);
WIRE 16 -1 (-3825 125)(-3825 75);
WIRE 16 -1 (-3825 75)(-3575 75);
WIRE 16 -1 (-3825 75)(-3825 25);
WIRE 16 -1 (-3575 25)(-3825 25);
WIRE 16 -1 (-3825 -25)(-3575 -25);
WIRE 16 -1 (-3825 25)(-3825 -25);
WIRE 16 -1 (-3825 -25)(-3825 -75);
WIRE 16 -1 (-3825 -75)(-3575 -75);
WIRE 16 -1 (-3825 -75)(-3825 -125);
WIRE 16 -1 (-3825 -125)(-3575 -125);
WIRE 16 -1 (-3825 -125)(-3825 -175);
WIRE 16 -1 (-3825 -175)(-3575 -175);
WIRE 16 -1 (-925 3725)(-1175 3725);
WIRE 16 -1 (-925 3675)(-1175 3675);
WIRE 16 -1 (-925 3725)(-925 3675);
WIRE 16 -1 (-925 3625)(-1175 3625);
WIRE 16 -1 (-925 3675)(-925 3625);
WIRE 16 -1 (-925 3575)(-1175 3575);
WIRE 16 -1 (-925 3625)(-925 3575);
WIRE 16 -1 (-1175 3525)(-925 3525);
WIRE 16 -1 (-925 3525)(-925 3575);
WIRE 16 -1 (-925 3475)(-1175 3475);
WIRE 16 -1 (-925 3475)(-925 3525);
WIRE 16 -1 (-925 3425)(-1175 3425);
WIRE 16 -1 (-925 3475)(-925 3425);
WIRE 16 -1 (-925 3375)(-1175 3375);
WIRE 16 -1 (-925 3425)(-925 3375);
WIRE 16 -1 (-925 3325)(-1175 3325);
WIRE 16 -1 (-925 3375)(-925 3325);
WIRE 16 -1 (-925 3275)(-1175 3275);
WIRE 16 -1 (-925 3325)(-925 3275);
WIRE 16 -1 (-925 3225)(-1175 3225);
WIRE 16 -1 (-925 3275)(-925 3225);
WIRE 16 -1 (-925 3175)(-1175 3175);
WIRE 16 -1 (-925 3225)(-925 3175);
WIRE 16 -1 (-925 3125)(-1175 3125);
WIRE 16 -1 (-925 3175)(-925 3125);
WIRE 16 -1 (-925 3075)(-1175 3075);
WIRE 16 -1 (-925 3125)(-925 3075);
WIRE 16 -1 (-1175 3025)(-925 3025);
WIRE 16 -1 (-925 3075)(-925 3025);
WIRE 16 -1 (-1175 2975)(-925 2975);
WIRE 16 -1 (-925 3025)(-925 2975);
WIRE 16 -1 (-1175 2925)(-925 2925);
WIRE 16 -1 (-925 2975)(-925 2925);
WIRE 16 -1 (-1175 2875)(-925 2875);
WIRE 16 -1 (-925 2925)(-925 2875);
WIRE 16 -1 (-1175 2825)(-925 2825);
WIRE 16 -1 (-925 2875)(-925 2825);
WIRE 16 -1 (-1175 2775)(-925 2775);
WIRE 16 -1 (-925 2825)(-925 2775);
WIRE 16 -1 (-1175 2725)(-925 2725);
WIRE 16 -1 (-925 2775)(-925 2725);
WIRE 16 -1 (-1175 2675)(-925 2675);
WIRE 16 -1 (-925 2675)(-925 2725);
WIRE 16 -1 (-1175 2625)(-925 2625);
WIRE 16 -1 (-925 2675)(-925 2625);
WIRE 16 -1 (-925 2575)(-1175 2575);
WIRE 16 -1 (-925 2625)(-925 2575);
WIRE 16 -1 (-925 2525)(-1175 2525);
WIRE 16 -1 (-925 2575)(-925 2525);
WIRE 16 -1 (-925 2475)(-1175 2475);
WIRE 16 -1 (-925 2525)(-925 2475);
WIRE 16 -1 (-925 2425)(-1175 2425);
WIRE 16 -1 (-925 2475)(-925 2425);
WIRE 16 -1 (-1175 2375)(-925 2375);
WIRE 16 -1 (-925 2375)(-925 2425);
WIRE 16 -1 (-925 2325)(-1175 2325);
WIRE 16 -1 (-925 2325)(-925 2375);
WIRE 16 -1 (-925 2275)(-1175 2275);
WIRE 16 -1 (-925 2325)(-925 2275);
WIRE 16 -1 (-925 2225)(-1175 2225);
WIRE 16 -1 (-925 2275)(-925 2225);
WIRE 16 -1 (-925 2175)(-1175 2175);
WIRE 16 -1 (-925 2225)(-925 2175);
WIRE 16 -1 (-925 2125)(-1175 2125);
WIRE 16 -1 (-925 2175)(-925 2125);
WIRE 16 -1 (-925 2075)(-1175 2075);
WIRE 16 -1 (-925 2125)(-925 2075);
WIRE 16 -1 (-925 2025)(-1175 2025);
WIRE 16 -1 (-925 2075)(-925 2025);
WIRE 16 -1 (-925 1975)(-1175 1975);
WIRE 16 -1 (-925 2025)(-925 1975);
WIRE 16 -1 (-925 1925)(-1175 1925);
WIRE 16 -1 (-925 1975)(-925 1925);
WIRE 16 -1 (-1175 1875)(-925 1875);
WIRE 16 -1 (-925 1925)(-925 1875);
WIRE 16 -1 (-1175 1825)(-925 1825);
WIRE 16 -1 (-925 1875)(-925 1825);
WIRE 16 -1 (-1175 1775)(-925 1775);
WIRE 16 -1 (-925 1825)(-925 1775);
WIRE 16 -1 (-1175 1725)(-925 1725);
WIRE 16 -1 (-925 1775)(-925 1725);
WIRE 16 -1 (-1175 1675)(-925 1675);
WIRE 16 -1 (-925 1725)(-925 1675);
WIRE 16 -1 (-1175 1625)(-925 1625);
WIRE 16 -1 (-925 1675)(-925 1625);
WIRE 16 -1 (-1175 1575)(-925 1575);
WIRE 16 -1 (-925 1625)(-925 1575);
WIRE 16 -1 (-1175 1525)(-925 1525);
WIRE 16 -1 (-925 1525)(-925 1575);
WIRE 16 -1 (-1175 1475)(-925 1475);
WIRE 16 -1 (-925 1525)(-925 1475);
WIRE 16 -1 (-925 1425)(-1175 1425);
WIRE 16 -1 (-925 1475)(-925 1425);
WIRE 16 -1 (-925 1375)(-1175 1375);
WIRE 16 -1 (-925 1425)(-925 1375);
WIRE 16 -1 (-925 1325)(-1175 1325);
WIRE 16 -1 (-925 1375)(-925 1325);
WIRE 16 -1 (-925 1275)(-1175 1275);
WIRE 16 -1 (-925 1325)(-925 1275);
WIRE 16 -1 (-1175 1225)(-925 1225);
WIRE 16 -1 (-925 1225)(-925 1275);
WIRE 16 -1 (-925 1175)(-1175 1175);
WIRE 16 -1 (-925 1175)(-925 1225);
WIRE 16 -1 (-925 1125)(-1175 1125);
WIRE 16 -1 (-925 1175)(-925 1125);
WIRE 16 -1 (-925 1075)(-1175 1075);
WIRE 16 -1 (-925 1125)(-925 1075);
WIRE 16 -1 (-1175 1025)(-925 1025);
WIRE 16 -1 (-925 1075)(-925 1025);
WIRE 16 -1 (-1175 975)(-925 975);
WIRE 16 -1 (-925 1025)(-925 975);
WIRE 16 -1 (-1175 925)(-925 925);
WIRE 16 -1 (-925 975)(-925 925);
WIRE 16 -1 (-1175 875)(-925 875);
WIRE 16 -1 (-925 925)(-925 875);
WIRE 16 -1 (-1175 825)(-925 825);
WIRE 16 -1 (-925 875)(-925 825);
WIRE 16 -1 (-1175 775)(-925 775);
WIRE 16 -1 (-925 825)(-925 775);
WIRE 16 -1 (-1175 725)(-925 725);
WIRE 16 -1 (-925 775)(-925 725);
WIRE 16 -1 (-1175 675)(-925 675);
WIRE 16 -1 (-925 675)(-925 725);
WIRE 16 -1 (-1175 625)(-925 625);
WIRE 16 -1 (-925 675)(-925 625);
WIRE 16 -1 (-925 575)(-1175 575);
WIRE 16 -1 (-925 625)(-925 575);
WIRE 16 -1 (-925 525)(-1175 525);
WIRE 16 -1 (-925 575)(-925 525);
WIRE 16 -1 (-925 475)(-1175 475);
WIRE 16 -1 (-925 525)(-925 475);
WIRE 16 -1 (-925 425)(-1175 425);
WIRE 16 -1 (-925 475)(-925 425);
WIRE 16 -1 (-1175 375)(-925 375);
WIRE 16 -1 (-925 375)(-925 425);
WIRE 16 -1 (-925 325)(-1175 325);
WIRE 16 -1 (-925 325)(-925 375);
WIRE 16 -1 (-925 275)(-1175 275);
WIRE 16 -1 (-925 325)(-925 275);
WIRE 16 -1 (-925 225)(-1175 225);
WIRE 16 -1 (-925 275)(-925 225);
WIRE 16 -1 (-1175 175)(-925 175);
WIRE 16 -1 (-925 225)(-925 175);
WIRE 16 -1 (-1175 125)(-925 125);
WIRE 16 -1 (-925 175)(-925 125);
WIRE 16 -1 (-1175 75)(-925 75);
WIRE 16 -1 (-925 125)(-925 75);
WIRE 16 -1 (-1175 25)(-925 25);
WIRE 16 -1 (-925 75)(-925 25);
WIRE 16 -1 (-1175 -25)(-925 -25);
WIRE 16 -1 (-925 25)(-925 -25);
WIRE 16 -1 (-1175 -75)(-925 -75);
WIRE 16 -1 (-925 -25)(-925 -75);
WIRE 16 -1 (-1175 -125)(-925 -125);
WIRE 16 -1 (-925 -75)(-925 -125);
WIRE 16 -1 (-925 -175)(-925 -125);
WIRE 16 -1 (-1175 -175)(-925 -175);
WIRE 16 -1 (-525 3725)(-775 3725);
WIRE 16 -1 (-775 3725)(-775 3675);
WIRE 16 -1 (-525 3675)(-775 3675);
WIRE 16 -1 (-775 3675)(-775 3625);
WIRE 16 -1 (-525 3625)(-775 3625);
WIRE 16 -1 (-525 3575)(-775 3575);
WIRE 16 -1 (-775 3625)(-775 3575);
WIRE 16 -1 (-775 3575)(-775 3525);
WIRE 16 -1 (-525 3525)(-775 3525);
WIRE 16 -1 (-775 3525)(-775 3475);
WIRE 16 -1 (-525 3475)(-775 3475);
WIRE 16 -1 (-775 3475)(-775 3425);
WIRE 16 -1 (-525 3425)(-775 3425);
WIRE 16 -1 (-775 3425)(-775 3375);
WIRE 16 -1 (-525 3375)(-775 3375);
WIRE 16 -1 (-775 3375)(-775 3325);
WIRE 16 -1 (-525 3325)(-775 3325);
WIRE 16 -1 (-775 3325)(-775 3275);
WIRE 16 -1 (-525 3275)(-775 3275);
WIRE 16 -1 (-775 3275)(-775 3225);
WIRE 16 -1 (-525 3225)(-775 3225);
WIRE 16 -1 (-775 3225)(-775 3175);
WIRE 16 -1 (-525 3175)(-775 3175);
WIRE 16 -1 (-775 3175)(-775 3125);
WIRE 16 -1 (-525 3125)(-775 3125);
WIRE 16 -1 (-775 3125)(-775 3075);
WIRE 16 -1 (-525 3075)(-775 3075);
WIRE 16 -1 (-775 3025)(-525 3025);
WIRE 16 -1 (-775 3075)(-775 3025);
WIRE 16 -1 (-775 3025)(-775 2975);
WIRE 16 -1 (-775 2975)(-525 2975);
WIRE 16 -1 (-775 2975)(-775 2925);
WIRE 16 -1 (-775 2925)(-525 2925);
WIRE 16 -1 (-775 2925)(-775 2875);
WIRE 16 -1 (-775 2875)(-525 2875);
WIRE 16 -1 (-775 2875)(-775 2825);
WIRE 16 -1 (-775 2825)(-525 2825);
WIRE 16 -1 (-775 2825)(-775 2775);
WIRE 16 -1 (-775 2775)(-525 2775);
WIRE 16 -1 (-775 2775)(-775 2725);
WIRE 16 -1 (-775 2725)(-525 2725);
WIRE 16 -1 (-775 2725)(-775 2675);
WIRE 16 -1 (-775 2675)(-525 2675);
WIRE 16 -1 (-775 2675)(-775 2625);
WIRE 16 -1 (-775 2625)(-525 2625);
WIRE 16 -1 (-775 2625)(-775 2575);
WIRE 16 -1 (-775 2575)(-525 2575);
WIRE 16 -1 (-775 2525)(-525 2525);
WIRE 16 -1 (-775 2575)(-775 2525);
WIRE 16 -1 (-775 2525)(-775 2475);
WIRE 16 -1 (-775 2475)(-525 2475);
WIRE 16 -1 (-775 2475)(-775 2425);
WIRE 16 -1 (-775 2425)(-525 2425);
WIRE 16 -1 (-775 2425)(-775 2375);
WIRE 16 -1 (-775 2375)(-525 2375);
WIRE 16 -1 (-775 2375)(-775 2325);
WIRE 16 -1 (-775 2325)(-525 2325);
WIRE 16 -1 (-775 2325)(-775 2275);
WIRE 16 -1 (-775 2275)(-525 2275);
WIRE 16 -1 (-775 2275)(-775 2225);
WIRE 16 -1 (-775 2225)(-525 2225);
WIRE 16 -1 (-775 2225)(-775 2175);
WIRE 16 -1 (-775 2175)(-525 2175);
WIRE 16 -1 (-775 2175)(-775 2125);
WIRE 16 -1 (-775 2125)(-525 2125);
WIRE 16 -1 (-775 2125)(-775 2075);
WIRE 16 -1 (-775 2075)(-525 2075);
WIRE 16 -1 (-775 2025)(-525 2025);
WIRE 16 -1 (-775 2075)(-775 2025);
WIRE 16 -1 (-775 2025)(-775 1975);
WIRE 16 -1 (-775 1975)(-525 1975);
WIRE 16 -1 (-775 1975)(-775 1925);
WIRE 16 -1 (-775 1925)(-525 1925);
WIRE 16 -1 (-775 1925)(-775 1875);
WIRE 16 -1 (-775 1875)(-525 1875);
WIRE 16 -1 (-775 1875)(-775 1825);
WIRE 16 -1 (-775 1825)(-525 1825);
WIRE 16 -1 (-775 1825)(-775 1775);
WIRE 16 -1 (-775 1775)(-525 1775);
WIRE 16 -1 (-775 1775)(-775 1725);
WIRE 16 -1 (-775 1725)(-525 1725);
WIRE 16 -1 (-775 1725)(-775 1675);
WIRE 16 -1 (-525 1675)(-775 1675);
WIRE 16 -1 (-775 1675)(-775 1625);
WIRE 16 -1 (-775 1625)(-525 1625);
WIRE 16 -1 (-775 1625)(-775 1575);
WIRE 16 -1 (-775 1575)(-525 1575);
WIRE 16 -1 (-775 1525)(-525 1525);
WIRE 16 -1 (-775 1575)(-775 1525);
WIRE 16 -1 (-775 1525)(-775 1475);
WIRE 16 -1 (-775 1475)(-525 1475);
WIRE 16 -1 (-775 1475)(-775 1425);
WIRE 16 -1 (-775 1425)(-525 1425);
WIRE 16 -1 (-775 1425)(-775 1375);
WIRE 16 -1 (-775 1375)(-525 1375);
WIRE 16 -1 (-775 1375)(-775 1325);
WIRE 16 -1 (-775 1325)(-525 1325);
WIRE 16 -1 (-775 1325)(-775 1275);
WIRE 16 -1 (-775 1275)(-525 1275);
WIRE 16 -1 (-775 1275)(-775 1225);
WIRE 16 -1 (-775 1225)(-525 1225);
WIRE 16 -1 (-775 1225)(-775 1175);
WIRE 16 -1 (-775 1175)(-525 1175);
WIRE 16 -1 (-775 1175)(-775 1125);
WIRE 16 -1 (-775 1125)(-525 1125);
WIRE 16 -1 (-775 1125)(-775 1075);
WIRE 16 -1 (-775 1075)(-525 1075);
WIRE 16 -1 (-775 1075)(-775 1025);
WIRE 16 -1 (-775 1025)(-525 1025);
WIRE 16 -1 (-775 975)(-525 975);
WIRE 16 -1 (-775 1025)(-775 975);
WIRE 16 -1 (-775 975)(-775 925);
WIRE 16 -1 (-775 925)(-525 925);
WIRE 16 -1 (-775 925)(-775 875);
WIRE 16 -1 (-775 875)(-525 875);
WIRE 16 -1 (-775 875)(-775 825);
WIRE 16 -1 (-775 825)(-525 825);
WIRE 16 -1 (-775 825)(-775 775);
WIRE 16 -1 (-775 775)(-525 775);
WIRE 16 -1 (-775 775)(-775 725);
WIRE 16 -1 (-775 725)(-525 725);
WIRE 16 -1 (-775 725)(-775 675);
WIRE 16 -1 (-525 675)(-775 675);
WIRE 16 -1 (-775 675)(-775 625);
WIRE 16 -1 (-775 625)(-525 625);
WIRE 16 -1 (-775 625)(-775 575);
WIRE 16 -1 (-775 575)(-525 575);
WIRE 16 -1 (-775 575)(-775 525);
WIRE 16 -1 (-775 525)(-525 525);
WIRE 16 -1 (-775 475)(-525 475);
WIRE 16 -1 (-775 525)(-775 475);
WIRE 16 -1 (-775 475)(-775 425);
WIRE 16 -1 (-775 425)(-525 425);
WIRE 16 -1 (-775 425)(-775 375);
WIRE 16 -1 (-525 375)(-775 375);
WIRE 16 -1 (-775 375)(-775 325);
WIRE 16 -1 (-775 325)(-525 325);
WIRE 16 -1 (-775 325)(-775 275);
WIRE 16 -1 (-775 275)(-525 275);
WIRE 16 -1 (-775 275)(-775 225);
WIRE 16 -1 (-775 225)(-525 225);
WIRE 16 -1 (-775 225)(-775 175);
WIRE 16 -1 (-775 175)(-525 175);
WIRE 16 -1 (-775 175)(-775 125);
WIRE 16 -1 (-775 125)(-525 125);
WIRE 16 -1 (-775 125)(-775 75);
WIRE 16 -1 (-775 75)(-525 75);
WIRE 16 -1 (-775 75)(-775 25);
WIRE 16 -1 (-525 25)(-775 25);
WIRE 16 -1 (-775 -25)(-525 -25);
WIRE 16 -1 (-775 25)(-775 -25);
WIRE 16 -1 (-775 -25)(-775 -75);
WIRE 16 -1 (-775 -75)(-525 -75);
WIRE 16 -1 (-775 -75)(-775 -125);
WIRE 16 -1 (-775 -125)(-525 -125);
WIRE 16 -1 (-775 -125)(-775 -175);
WIRE 16 -1 (-775 -175)(-525 -175);
WIRE 16 -1 (2500 3725)(2250 3725);
WIRE 16 -1 (2250 3725)(2250 3675);
WIRE 16 -1 (2500 3675)(2250 3675);
WIRE 16 -1 (2250 3675)(2250 3625);
WIRE 16 -1 (2500 3625)(2250 3625);
WIRE 16 -1 (2500 3575)(2250 3575);
WIRE 16 -1 (2250 3625)(2250 3575);
WIRE 16 -1 (2250 3575)(2250 3525);
WIRE 16 -1 (2500 3525)(2250 3525);
WIRE 16 -1 (2250 3525)(2250 3475);
WIRE 16 -1 (2500 3475)(2250 3475);
WIRE 16 -1 (2250 3475)(2250 3425);
WIRE 16 -1 (2500 3425)(2250 3425);
WIRE 16 -1 (2250 3425)(2250 3375);
WIRE 16 -1 (2500 3375)(2250 3375);
WIRE 16 -1 (2250 3375)(2250 3325);
WIRE 16 -1 (2500 3325)(2250 3325);
WIRE 16 -1 (2250 3325)(2250 3275);
WIRE 16 -1 (2500 3275)(2250 3275);
WIRE 16 -1 (2250 3275)(2250 3225);
WIRE 16 -1 (2500 3225)(2250 3225);
WIRE 16 -1 (2250 3225)(2250 3175);
WIRE 16 -1 (2500 3175)(2250 3175);
WIRE 16 -1 (2250 3175)(2250 3125);
WIRE 16 -1 (2500 3125)(2250 3125);
WIRE 16 -1 (2250 3125)(2250 3075);
WIRE 16 -1 (2500 3075)(2250 3075);
WIRE 16 -1 (2250 3025)(2500 3025);
WIRE 16 -1 (2250 3075)(2250 3025);
WIRE 16 -1 (2250 3025)(2250 2975);
WIRE 16 -1 (2250 2975)(2500 2975);
WIRE 16 -1 (2250 2975)(2250 2925);
WIRE 16 -1 (2250 2925)(2500 2925);
WIRE 16 -1 (2250 2925)(2250 2875);
WIRE 16 -1 (2250 2875)(2500 2875);
WIRE 16 -1 (2250 2875)(2250 2825);
WIRE 16 -1 (2250 2825)(2500 2825);
WIRE 16 -1 (2250 2825)(2250 2775);
WIRE 16 -1 (2250 2775)(2500 2775);
WIRE 16 -1 (2250 2775)(2250 2725);
WIRE 16 -1 (2250 2725)(2500 2725);
WIRE 16 -1 (2250 2725)(2250 2675);
WIRE 16 -1 (2250 2675)(2500 2675);
WIRE 16 -1 (2250 2675)(2250 2625);
WIRE 16 -1 (2250 2625)(2500 2625);
WIRE 16 -1 (2250 2625)(2250 2575);
WIRE 16 -1 (2250 2575)(2500 2575);
WIRE 16 -1 (2250 2525)(2500 2525);
WIRE 16 -1 (2250 2575)(2250 2525);
WIRE 16 -1 (2250 2525)(2250 2475);
WIRE 16 -1 (2250 2475)(2500 2475);
WIRE 16 -1 (2250 2475)(2250 2425);
WIRE 16 -1 (2250 2425)(2500 2425);
WIRE 16 -1 (2250 2425)(2250 2375);
WIRE 16 -1 (2250 2375)(2500 2375);
WIRE 16 -1 (2250 2375)(2250 2325);
WIRE 16 -1 (2250 2325)(2500 2325);
WIRE 16 -1 (2250 2325)(2250 2275);
WIRE 16 -1 (2250 2275)(2500 2275);
WIRE 16 -1 (2250 2275)(2250 2225);
WIRE 16 -1 (2250 2225)(2500 2225);
WIRE 16 -1 (2250 2225)(2250 2175);
WIRE 16 -1 (2250 2175)(2500 2175);
WIRE 16 -1 (2250 2175)(2250 2125);
WIRE 16 -1 (2250 2125)(2500 2125);
WIRE 16 -1 (2250 2125)(2250 2075);
WIRE 16 -1 (2250 2075)(2500 2075);
WIRE 16 -1 (2250 2025)(2500 2025);
WIRE 16 -1 (2250 2075)(2250 2025);
WIRE 16 -1 (2250 2025)(2250 1975);
WIRE 16 -1 (2250 1975)(2500 1975);
WIRE 16 -1 (2250 1975)(2250 1925);
WIRE 16 -1 (2250 1925)(2500 1925);
WIRE 16 -1 (2250 1925)(2250 1875);
WIRE 16 -1 (2250 1875)(2500 1875);
WIRE 16 -1 (2250 1875)(2250 1825);
WIRE 16 -1 (2250 1825)(2500 1825);
WIRE 16 -1 (2250 1825)(2250 1775);
WIRE 16 -1 (2250 1775)(2500 1775);
WIRE 16 -1 (2250 1775)(2250 1725);
WIRE 16 -1 (2250 1725)(2500 1725);
WIRE 16 -1 (2250 1725)(2250 1675);
WIRE 16 -1 (2500 1675)(2250 1675);
WIRE 16 -1 (2250 1675)(2250 1625);
WIRE 16 -1 (2250 1625)(2500 1625);
WIRE 16 -1 (2250 1625)(2250 1575);
WIRE 16 -1 (2250 1575)(2500 1575);
WIRE 16 -1 (2250 1525)(2500 1525);
WIRE 16 -1 (2250 1575)(2250 1525);
WIRE 16 -1 (2250 1525)(2250 1475);
WIRE 16 -1 (2250 1475)(2500 1475);
WIRE 16 -1 (2250 1475)(2250 1425);
WIRE 16 -1 (2250 1425)(2500 1425);
WIRE 16 -1 (2250 1425)(2250 1375);
WIRE 16 -1 (2250 1375)(2500 1375);
WIRE 16 -1 (2250 1375)(2250 1325);
WIRE 16 -1 (2250 1325)(2500 1325);
WIRE 16 -1 (2250 1325)(2250 1275);
WIRE 16 -1 (2250 1275)(2500 1275);
WIRE 16 -1 (2250 1275)(2250 1225);
WIRE 16 -1 (2250 1225)(2500 1225);
WIRE 16 -1 (2250 1225)(2250 1175);
WIRE 16 -1 (2250 1175)(2500 1175);
WIRE 16 -1 (2250 1175)(2250 1125);
WIRE 16 -1 (2250 1125)(2500 1125);
WIRE 16 -1 (2250 1125)(2250 1075);
WIRE 16 -1 (2250 1075)(2500 1075);
WIRE 16 -1 (2250 1075)(2250 1025);
WIRE 16 -1 (2250 1025)(2500 1025);
WIRE 16 -1 (2250 975)(2500 975);
WIRE 16 -1 (2250 1025)(2250 975);
WIRE 16 -1 (2250 975)(2250 925);
WIRE 16 -1 (2250 925)(2500 925);
WIRE 16 -1 (2250 925)(2250 875);
WIRE 16 -1 (2250 875)(2500 875);
WIRE 16 -1 (2250 875)(2250 825);
WIRE 16 -1 (2250 825)(2500 825);
WIRE 16 -1 (2250 825)(2250 775);
WIRE 16 -1 (2250 775)(2500 775);
WIRE 16 -1 (2250 775)(2250 725);
WIRE 16 -1 (2250 725)(2500 725);
WIRE 16 -1 (2250 725)(2250 675);
WIRE 16 -1 (2500 675)(2250 675);
WIRE 16 -1 (2250 675)(2250 625);
WIRE 16 -1 (2250 625)(2500 625);
WIRE 16 -1 (2250 625)(2250 575);
WIRE 16 -1 (2250 575)(2500 575);
WIRE 16 -1 (2250 575)(2250 525);
WIRE 16 -1 (2250 525)(2500 525);
WIRE 16 -1 (2250 475)(2500 475);
WIRE 16 -1 (2250 525)(2250 475);
WIRE 16 -1 (2250 475)(2250 425);
WIRE 16 -1 (2250 425)(2500 425);
WIRE 16 -1 (2250 425)(2250 375);
WIRE 16 -1 (2500 375)(2250 375);
WIRE 16 -1 (2250 375)(2250 325);
WIRE 16 -1 (2250 325)(2500 325);
WIRE 16 -1 (2250 325)(2250 275);
WIRE 16 -1 (2250 275)(2500 275);
WIRE 16 -1 (2250 275)(2250 225);
WIRE 16 -1 (2250 225)(2500 225);
WIRE 16 -1 (2250 225)(2250 175);
WIRE 16 -1 (2250 175)(2500 175);
WIRE 16 -1 (2250 175)(2250 125);
WIRE 16 -1 (2250 125)(2500 125);
WIRE 16 -1 (2250 125)(2250 75);
WIRE 16 -1 (2250 75)(2500 75);
WIRE 16 -1 (2250 75)(2250 25);
WIRE 16 -1 (2500 25)(2250 25);
WIRE 16 -1 (2250 -25)(2500 -25);
WIRE 16 -1 (2250 25)(2250 -25);
WIRE 16 -1 (2250 -25)(2250 -75);
WIRE 16 -1 (2250 -75)(2500 -75);
WIRE 16 -1 (2250 -75)(2250 -125);
WIRE 16 -1 (2250 -125)(2500 -125);
WIRE 16 -1 (2250 -125)(2250 -175);
WIRE 16 -1 (2250 -175)(2500 -175);
WIRE 16 -1 (2125 3725)(1875 3725);
WIRE 16 -1 (2125 3675)(1875 3675);
WIRE 16 -1 (2125 3725)(2125 3675);
WIRE 16 -1 (2125 3625)(1875 3625);
WIRE 16 -1 (2125 3675)(2125 3625);
WIRE 16 -1 (2125 3575)(1875 3575);
WIRE 16 -1 (2125 3625)(2125 3575);
WIRE 16 -1 (1875 3525)(2125 3525);
WIRE 16 -1 (2125 3525)(2125 3575);
WIRE 16 -1 (2125 3475)(1875 3475);
WIRE 16 -1 (2125 3475)(2125 3525);
WIRE 16 -1 (2125 3425)(1875 3425);
WIRE 16 -1 (2125 3475)(2125 3425);
WIRE 16 -1 (2125 3375)(1875 3375);
WIRE 16 -1 (2125 3425)(2125 3375);
WIRE 16 -1 (2125 3325)(1875 3325);
WIRE 16 -1 (2125 3375)(2125 3325);
WIRE 16 -1 (2125 3275)(1875 3275);
WIRE 16 -1 (2125 3325)(2125 3275);
WIRE 16 -1 (2125 3225)(1875 3225);
WIRE 16 -1 (2125 3275)(2125 3225);
WIRE 16 -1 (2125 3175)(1875 3175);
WIRE 16 -1 (2125 3225)(2125 3175);
WIRE 16 -1 (2125 3125)(1875 3125);
WIRE 16 -1 (2125 3175)(2125 3125);
WIRE 16 -1 (2125 3075)(1875 3075);
WIRE 16 -1 (2125 3125)(2125 3075);
WIRE 16 -1 (1875 3025)(2125 3025);
WIRE 16 -1 (2125 3075)(2125 3025);
WIRE 16 -1 (1875 2975)(2125 2975);
WIRE 16 -1 (2125 3025)(2125 2975);
WIRE 16 -1 (1875 2925)(2125 2925);
WIRE 16 -1 (2125 2975)(2125 2925);
WIRE 16 -1 (1875 2875)(2125 2875);
WIRE 16 -1 (2125 2925)(2125 2875);
WIRE 16 -1 (1875 2825)(2125 2825);
WIRE 16 -1 (2125 2875)(2125 2825);
WIRE 16 -1 (1875 2775)(2125 2775);
WIRE 16 -1 (2125 2825)(2125 2775);
WIRE 16 -1 (1875 2725)(2125 2725);
WIRE 16 -1 (2125 2775)(2125 2725);
WIRE 16 -1 (1875 2675)(2125 2675);
WIRE 16 -1 (2125 2675)(2125 2725);
WIRE 16 -1 (1875 2625)(2125 2625);
WIRE 16 -1 (2125 2675)(2125 2625);
WIRE 16 -1 (2125 2575)(1875 2575);
WIRE 16 -1 (2125 2625)(2125 2575);
WIRE 16 -1 (2125 2525)(1875 2525);
WIRE 16 -1 (2125 2575)(2125 2525);
WIRE 16 -1 (2125 2475)(1875 2475);
WIRE 16 -1 (2125 2525)(2125 2475);
WIRE 16 -1 (2125 2425)(1875 2425);
WIRE 16 -1 (2125 2475)(2125 2425);
WIRE 16 -1 (1875 2375)(2125 2375);
WIRE 16 -1 (2125 2375)(2125 2425);
WIRE 16 -1 (2125 2325)(1875 2325);
WIRE 16 -1 (2125 2325)(2125 2375);
WIRE 16 -1 (2125 2275)(1875 2275);
WIRE 16 -1 (2125 2325)(2125 2275);
WIRE 16 -1 (2125 2225)(1875 2225);
WIRE 16 -1 (2125 2275)(2125 2225);
WIRE 16 -1 (2125 2175)(1875 2175);
WIRE 16 -1 (2125 2225)(2125 2175);
WIRE 16 -1 (2125 2125)(1875 2125);
WIRE 16 -1 (2125 2175)(2125 2125);
WIRE 16 -1 (2125 2075)(1875 2075);
WIRE 16 -1 (2125 2125)(2125 2075);
WIRE 16 -1 (2125 2025)(1875 2025);
WIRE 16 -1 (2125 2075)(2125 2025);
WIRE 16 -1 (2125 1975)(1875 1975);
WIRE 16 -1 (2125 2025)(2125 1975);
WIRE 16 -1 (2125 1925)(1875 1925);
WIRE 16 -1 (2125 1975)(2125 1925);
WIRE 16 -1 (1875 1875)(2125 1875);
WIRE 16 -1 (2125 1925)(2125 1875);
WIRE 16 -1 (1875 1825)(2125 1825);
WIRE 16 -1 (2125 1875)(2125 1825);
WIRE 16 -1 (1875 1775)(2125 1775);
WIRE 16 -1 (2125 1825)(2125 1775);
WIRE 16 -1 (1875 1725)(2125 1725);
WIRE 16 -1 (2125 1775)(2125 1725);
WIRE 16 -1 (1875 1675)(2125 1675);
WIRE 16 -1 (2125 1725)(2125 1675);
WIRE 16 -1 (1875 1625)(2125 1625);
WIRE 16 -1 (2125 1675)(2125 1625);
WIRE 16 -1 (1875 1575)(2125 1575);
WIRE 16 -1 (2125 1625)(2125 1575);
WIRE 16 -1 (1875 1525)(2125 1525);
WIRE 16 -1 (2125 1525)(2125 1575);
WIRE 16 -1 (1875 1475)(2125 1475);
WIRE 16 -1 (2125 1525)(2125 1475);
WIRE 16 -1 (2125 1425)(1875 1425);
WIRE 16 -1 (2125 1475)(2125 1425);
WIRE 16 -1 (2125 1375)(1875 1375);
WIRE 16 -1 (2125 1425)(2125 1375);
WIRE 16 -1 (2125 1325)(1875 1325);
WIRE 16 -1 (2125 1375)(2125 1325);
WIRE 16 -1 (2125 1275)(1875 1275);
WIRE 16 -1 (2125 1325)(2125 1275);
WIRE 16 -1 (1875 1225)(2125 1225);
WIRE 16 -1 (2125 1225)(2125 1275);
WIRE 16 -1 (2125 1175)(1875 1175);
WIRE 16 -1 (2125 1175)(2125 1225);
WIRE 16 -1 (2125 1125)(1875 1125);
WIRE 16 -1 (2125 1175)(2125 1125);
WIRE 16 -1 (2125 1075)(1875 1075);
WIRE 16 -1 (2125 1125)(2125 1075);
WIRE 16 -1 (1875 1025)(2125 1025);
WIRE 16 -1 (2125 1075)(2125 1025);
WIRE 16 -1 (1875 975)(2125 975);
WIRE 16 -1 (2125 1025)(2125 975);
WIRE 16 -1 (1875 925)(2125 925);
WIRE 16 -1 (2125 975)(2125 925);
WIRE 16 -1 (1875 875)(2125 875);
WIRE 16 -1 (2125 925)(2125 875);
WIRE 16 -1 (1875 825)(2125 825);
WIRE 16 -1 (2125 875)(2125 825);
WIRE 16 -1 (1875 775)(2125 775);
WIRE 16 -1 (2125 825)(2125 775);
WIRE 16 -1 (1875 725)(2125 725);
WIRE 16 -1 (2125 775)(2125 725);
WIRE 16 -1 (1875 675)(2125 675);
WIRE 16 -1 (2125 675)(2125 725);
WIRE 16 -1 (1875 625)(2125 625);
WIRE 16 -1 (2125 675)(2125 625);
WIRE 16 -1 (2125 575)(1875 575);
WIRE 16 -1 (2125 625)(2125 575);
WIRE 16 -1 (2125 525)(1875 525);
WIRE 16 -1 (2125 575)(2125 525);
WIRE 16 -1 (2125 475)(1875 475);
WIRE 16 -1 (2125 525)(2125 475);
WIRE 16 -1 (2125 425)(1875 425);
WIRE 16 -1 (2125 475)(2125 425);
WIRE 16 -1 (1875 375)(2125 375);
WIRE 16 -1 (2125 375)(2125 425);
WIRE 16 -1 (2125 325)(1875 325);
WIRE 16 -1 (2125 325)(2125 375);
WIRE 16 -1 (2125 275)(1875 275);
WIRE 16 -1 (2125 325)(2125 275);
WIRE 16 -1 (2125 225)(1875 225);
WIRE 16 -1 (2125 275)(2125 225);
WIRE 16 -1 (1875 175)(2125 175);
WIRE 16 -1 (2125 225)(2125 175);
WIRE 16 -1 (1875 125)(2125 125);
WIRE 16 -1 (2125 175)(2125 125);
WIRE 16 -1 (1875 75)(2125 75);
WIRE 16 -1 (2125 125)(2125 75);
WIRE 16 -1 (1875 25)(2125 25);
WIRE 16 -1 (2125 75)(2125 25);
WIRE 16 -1 (1875 -25)(2125 -25);
WIRE 16 -1 (2125 25)(2125 -25);
WIRE 16 -1 (1875 -75)(2125 -75);
WIRE 16 -1 (2125 -25)(2125 -75);
WIRE 16 -1 (1875 -125)(2125 -125);
WIRE 16 -1 (2125 -75)(2125 -125);
WIRE 16 -1 (2125 -175)(2125 -125);
WIRE 16 -1 (1875 -175)(2125 -175);
WIRE 16 -1 (5150 3725)(4900 3725);
WIRE 16 -1 (5150 3675)(4900 3675);
WIRE 16 -1 (5150 3725)(5150 3675);
WIRE 16 -1 (5150 3625)(4900 3625);
WIRE 16 -1 (5150 3675)(5150 3625);
WIRE 16 -1 (5150 3575)(4900 3575);
WIRE 16 -1 (5150 3625)(5150 3575);
WIRE 16 -1 (4900 3525)(5150 3525);
WIRE 16 -1 (5150 3525)(5150 3575);
WIRE 16 -1 (5150 3475)(4900 3475);
WIRE 16 -1 (5150 3475)(5150 3525);
WIRE 16 -1 (5150 3425)(4900 3425);
WIRE 16 -1 (5150 3475)(5150 3425);
WIRE 16 -1 (5150 3375)(4900 3375);
WIRE 16 -1 (5150 3425)(5150 3375);
WIRE 16 -1 (5150 3325)(4900 3325);
WIRE 16 -1 (5150 3375)(5150 3325);
WIRE 16 -1 (5150 3275)(4900 3275);
WIRE 16 -1 (5150 3325)(5150 3275);
WIRE 16 -1 (5150 3225)(4900 3225);
WIRE 16 -1 (5150 3275)(5150 3225);
WIRE 16 -1 (5150 3175)(4900 3175);
WIRE 16 -1 (5150 3225)(5150 3175);
WIRE 16 -1 (5150 3125)(4900 3125);
WIRE 16 -1 (5150 3175)(5150 3125);
WIRE 16 -1 (5150 3075)(4900 3075);
WIRE 16 -1 (5150 3125)(5150 3075);
WIRE 16 -1 (4900 3025)(5150 3025);
WIRE 16 -1 (5150 3075)(5150 3025);
WIRE 16 -1 (4900 2975)(5150 2975);
WIRE 16 -1 (5150 3025)(5150 2975);
WIRE 16 -1 (4900 2925)(5150 2925);
WIRE 16 -1 (5150 2975)(5150 2925);
WIRE 16 -1 (4900 2875)(5150 2875);
WIRE 16 -1 (5150 2925)(5150 2875);
WIRE 16 -1 (4900 2825)(5150 2825);
WIRE 16 -1 (5150 2875)(5150 2825);
WIRE 16 -1 (4900 2775)(5150 2775);
WIRE 16 -1 (5150 2825)(5150 2775);
WIRE 16 -1 (4900 2725)(5150 2725);
WIRE 16 -1 (5150 2775)(5150 2725);
WIRE 16 -1 (4900 2675)(5150 2675);
WIRE 16 -1 (5150 2675)(5150 2725);
WIRE 16 -1 (4900 2625)(5150 2625);
WIRE 16 -1 (5150 2675)(5150 2625);
WIRE 16 -1 (5150 2575)(4900 2575);
WIRE 16 -1 (5150 2625)(5150 2575);
WIRE 16 -1 (5150 2525)(4900 2525);
WIRE 16 -1 (5150 2575)(5150 2525);
WIRE 16 -1 (5150 2475)(4900 2475);
WIRE 16 -1 (5150 2525)(5150 2475);
WIRE 16 -1 (5150 2425)(4900 2425);
WIRE 16 -1 (5150 2475)(5150 2425);
WIRE 16 -1 (4900 2375)(5150 2375);
WIRE 16 -1 (5150 2375)(5150 2425);
WIRE 16 -1 (5150 2325)(4900 2325);
WIRE 16 -1 (5150 2325)(5150 2375);
WIRE 16 -1 (5150 2275)(4900 2275);
WIRE 16 -1 (5150 2325)(5150 2275);
WIRE 16 -1 (5150 2225)(4900 2225);
WIRE 16 -1 (5150 2275)(5150 2225);
WIRE 16 -1 (5150 2175)(4900 2175);
WIRE 16 -1 (5150 2225)(5150 2175);
WIRE 16 -1 (5150 2125)(4900 2125);
WIRE 16 -1 (5150 2175)(5150 2125);
WIRE 16 -1 (5150 2075)(4900 2075);
WIRE 16 -1 (5150 2125)(5150 2075);
WIRE 16 -1 (5150 2025)(4900 2025);
WIRE 16 -1 (5150 2075)(5150 2025);
WIRE 16 -1 (5150 1975)(4900 1975);
WIRE 16 -1 (5150 2025)(5150 1975);
WIRE 16 -1 (5150 1925)(4900 1925);
WIRE 16 -1 (5150 1975)(5150 1925);
WIRE 16 -1 (4900 1875)(5150 1875);
WIRE 16 -1 (5150 1925)(5150 1875);
WIRE 16 -1 (4900 1825)(5150 1825);
WIRE 16 -1 (5150 1875)(5150 1825);
WIRE 16 -1 (4900 1775)(5150 1775);
WIRE 16 -1 (5150 1825)(5150 1775);
WIRE 16 -1 (4900 1725)(5150 1725);
WIRE 16 -1 (5150 1775)(5150 1725);
WIRE 16 -1 (4900 1675)(5150 1675);
WIRE 16 -1 (5150 1725)(5150 1675);
WIRE 16 -1 (4900 1625)(5150 1625);
WIRE 16 -1 (5150 1675)(5150 1625);
WIRE 16 -1 (4900 1575)(5150 1575);
WIRE 16 -1 (5150 1625)(5150 1575);
WIRE 16 -1 (4900 1525)(5150 1525);
WIRE 16 -1 (5150 1525)(5150 1575);
WIRE 16 -1 (4900 1475)(5150 1475);
WIRE 16 -1 (5150 1525)(5150 1475);
WIRE 16 -1 (5150 1425)(4900 1425);
WIRE 16 -1 (5150 1475)(5150 1425);
WIRE 16 -1 (5150 1375)(4900 1375);
WIRE 16 -1 (5150 1425)(5150 1375);
WIRE 16 -1 (5150 1325)(4900 1325);
WIRE 16 -1 (5150 1375)(5150 1325);
WIRE 16 -1 (5150 1275)(4900 1275);
WIRE 16 -1 (5150 1325)(5150 1275);
WIRE 16 -1 (4900 1225)(5150 1225);
WIRE 16 -1 (5150 1225)(5150 1275);
WIRE 16 -1 (5150 1175)(4900 1175);
WIRE 16 -1 (5150 1175)(5150 1225);
WIRE 16 -1 (5150 1125)(4900 1125);
WIRE 16 -1 (5150 1175)(5150 1125);
WIRE 16 -1 (5150 1075)(4900 1075);
WIRE 16 -1 (5150 1125)(5150 1075);
WIRE 16 -1 (4900 1025)(5150 1025);
WIRE 16 -1 (5150 1075)(5150 1025);
WIRE 16 -1 (4900 975)(5150 975);
WIRE 16 -1 (5150 1025)(5150 975);
WIRE 16 -1 (4900 925)(5150 925);
WIRE 16 -1 (5150 975)(5150 925);
WIRE 16 -1 (4900 875)(5150 875);
WIRE 16 -1 (5150 925)(5150 875);
WIRE 16 -1 (4900 825)(5150 825);
WIRE 16 -1 (5150 875)(5150 825);
WIRE 16 -1 (4900 775)(5150 775);
WIRE 16 -1 (5150 825)(5150 775);
WIRE 16 -1 (4900 725)(5150 725);
WIRE 16 -1 (5150 775)(5150 725);
WIRE 16 -1 (4900 675)(5150 675);
WIRE 16 -1 (5150 675)(5150 725);
WIRE 16 -1 (4900 625)(5150 625);
WIRE 16 -1 (5150 675)(5150 625);
WIRE 16 -1 (5150 575)(4900 575);
WIRE 16 -1 (5150 625)(5150 575);
WIRE 16 -1 (5150 525)(4900 525);
WIRE 16 -1 (5150 575)(5150 525);
WIRE 16 -1 (5150 475)(4900 475);
WIRE 16 -1 (5150 525)(5150 475);
WIRE 16 -1 (5150 425)(4900 425);
WIRE 16 -1 (5150 475)(5150 425);
WIRE 16 -1 (4900 375)(5150 375);
WIRE 16 -1 (5150 375)(5150 425);
WIRE 16 -1 (5150 325)(4900 325);
WIRE 16 -1 (5150 325)(5150 375);
WIRE 16 -1 (5150 275)(4900 275);
WIRE 16 -1 (5150 325)(5150 275);
WIRE 16 -1 (5150 225)(4900 225);
WIRE 16 -1 (5150 275)(5150 225);
WIRE 16 -1 (4900 175)(5150 175);
WIRE 16 -1 (5150 225)(5150 175);
WIRE 16 -1 (4900 125)(5150 125);
WIRE 16 -1 (5150 175)(5150 125);
WIRE 16 -1 (4900 75)(5150 75);
WIRE 16 -1 (5150 125)(5150 75);
WIRE 16 -1 (4900 25)(5150 25);
WIRE 16 -1 (5150 75)(5150 25);
WIRE 16 -1 (4900 -25)(5150 -25);
WIRE 16 -1 (5150 25)(5150 -25);
WIRE 16 -1 (4900 -75)(5150 -75);
WIRE 16 -1 (5150 -25)(5150 -75);
WIRE 16 -1 (4900 -125)(5150 -125);
WIRE 16 -1 (5150 -75)(5150 -125);
WIRE 16 -1 (5150 -175)(5150 -125);
WIRE 16 -1 (4900 -175)(5150 -175);
DOT 1 (2250 3425);
DOT 1 (2250 3375);
DOT 1 (2125 3375);
DOT 1 (-775 2875);
DOT 1 (-3825 3225);
DOT 1 (2250 -125);
DOT 1 (2250 -75);
DOT 1 (2125 25);
DOT 1 (-775 1825);
DOT 1 (-775 1575);
DOT 1 (-3825 1875);
DOT 1 (-775 2175);
DOT 1 (-925 2125);
DOT 1 (-3825 2675);
DOT 1 (5150 3675);
DOT 1 (5150 3625);
DOT 1 (5150 3575);
DOT 1 (5150 3525);
DOT 1 (5150 3475);
DOT 1 (5150 3425);
DOT 1 (5150 3375);
DOT 1 (5150 3325);
DOT 1 (5150 3225);
DOT 1 (5150 3175);
DOT 1 (5150 3275);
DOT 1 (5150 3075);
DOT 1 (5150 3125);
DOT 1 (5150 3025);
DOT 1 (5150 2925);
DOT 1 (5150 2975);
DOT 1 (5150 2825);
DOT 1 (5150 2875);
DOT 1 (5150 2775);
DOT 1 (5150 2725);
DOT 1 (5150 2675);
DOT 1 (5150 2575);
DOT 1 (5150 2525);
DOT 1 (5150 2625);
DOT 1 (5150 2425);
DOT 1 (5150 2475);
DOT 1 (5150 2275);
DOT 1 (5150 2325);
DOT 1 (5150 2375);
DOT 1 (5150 2175);
DOT 1 (5150 2225);
DOT 1 (5150 2025);
DOT 1 (5150 2075);
DOT 1 (5150 2125);
DOT 1 (5150 1975);
DOT 1 (5150 1925);
DOT 1 (5150 1875);
DOT 1 (5150 1825);
DOT 1 (5150 1775);
DOT 1 (5150 1725);
DOT 1 (5150 1675);
DOT 1 (5150 1625);
DOT 1 (5150 1525);
DOT 1 (5150 1575);
DOT 1 (5150 1475);
DOT 1 (5150 1425);
DOT 1 (5150 1375);
DOT 1 (5150 1325);
DOT 1 (5150 1275);
DOT 1 (5150 1225);
DOT 1 (5150 1125);
DOT 1 (5150 1175);
DOT 1 (5150 1025);
DOT 1 (5150 1075);
DOT 1 (5150 975);
DOT 1 (5150 925);
DOT 1 (5150 875);
DOT 1 (5150 775);
DOT 1 (5150 825);
DOT 1 (5150 725);
DOT 1 (5150 625);
DOT 1 (5150 675);
DOT 1 (5150 525);
DOT 1 (5150 575);
DOT 1 (5150 475);
DOT 1 (5150 425);
DOT 1 (5150 375);
DOT 1 (5150 275);
DOT 1 (5150 325);
DOT 1 (5150 225);
DOT 1 (5150 175);
DOT 1 (5150 125);
DOT 1 (5150 -25);
DOT 1 (5150 25);
DOT 1 (5150 75);
DOT 1 (2250 3675);
DOT 1 (2250 3575);
DOT 1 (2250 3625);
DOT 1 (2125 3675);
DOT 1 (2125 3625);
DOT 1 (2125 3575);
DOT 1 (2250 3525);
DOT 1 (2250 3475);
DOT 1 (2250 3325);
DOT 1 (2250 3275);
DOT 1 (2250 3225);
DOT 1 (2250 3175);
DOT 1 (2250 3125);
DOT 1 (2250 3075);
DOT 1 (2125 3525);
DOT 1 (2125 3475);
DOT 1 (2125 3425);
DOT 1 (2125 3325);
DOT 1 (2125 3275);
DOT 1 (2125 3225);
DOT 1 (2125 3175);
DOT 1 (2125 3125);
DOT 1 (2125 3075);
DOT 1 (2250 3025);
DOT 1 (2125 3025);
DOT 1 (2250 2975);
DOT 1 (2250 2925);
DOT 1 (2250 2875);
DOT 1 (2250 2825);
DOT 1 (2250 2775);
DOT 1 (2250 2725);
DOT 1 (2250 2675);
DOT 1 (2250 2625);
DOT 1 (2250 2575);
DOT 1 (2250 2525);
DOT 1 (2125 2975);
DOT 1 (2125 2925);
DOT 1 (2125 2875);
DOT 1 (2125 2825);
DOT 1 (2125 2775);
DOT 1 (2125 2675);
DOT 1 (2125 2725);
DOT 1 (2125 2625);
DOT 1 (2125 2575);
DOT 1 (2125 2525);
DOT 1 (2250 2475);
DOT 1 (2250 2425);
DOT 1 (2250 2375);
DOT 1 (2250 2325);
DOT 1 (2250 2275);
DOT 1 (2250 2225);
DOT 1 (2250 2175);
DOT 1 (2250 2125);
DOT 1 (2250 2075);
DOT 1 (2250 2025);
DOT 1 (2125 2475);
DOT 1 (2125 2425);
DOT 1 (2125 2375);
DOT 1 (2125 2325);
DOT 1 (2125 2275);
DOT 1 (2125 2225);
DOT 1 (2125 2175);
DOT 1 (2125 2125);
DOT 1 (2125 2075);
DOT 1 (2125 2025);
DOT 1 (2250 1975);
DOT 1 (2250 1925);
DOT 1 (2250 1875);
DOT 1 (2250 1825);
DOT 1 (2250 1775);
DOT 1 (2250 1725);
DOT 1 (2250 1675);
DOT 1 (2250 1625);
DOT 1 (2250 1525);
DOT 1 (2250 1575);
DOT 1 (2125 1975);
DOT 1 (2125 1925);
DOT 1 (2125 1875);
DOT 1 (2125 1825);
DOT 1 (2125 1775);
DOT 1 (2125 1725);
DOT 1 (2125 1675);
DOT 1 (2125 1625);
DOT 1 (2125 1525);
DOT 1 (2125 1575);
DOT 1 (2250 1475);
DOT 1 (2250 1425);
DOT 1 (2250 1375);
DOT 1 (2250 1275);
DOT 1 (2250 1325);
DOT 1 (2250 1225);
DOT 1 (2250 1175);
DOT 1 (2250 1125);
DOT 1 (2250 1075);
DOT 1 (2250 1025);
DOT 1 (2125 1475);
DOT 1 (2125 1425);
DOT 1 (2125 1375);
DOT 1 (2125 1325);
DOT 1 (2125 1275);
DOT 1 (2125 1225);
DOT 1 (2125 1175);
DOT 1 (2125 1125);
DOT 1 (2125 1075);
DOT 1 (2125 1025);
DOT 1 (2250 975);
DOT 1 (2125 975);
DOT 1 (2250 925);
DOT 1 (2250 875);
DOT 1 (2250 825);
DOT 1 (2250 775);
DOT 1 (2250 725);
DOT 1 (2250 675);
DOT 1 (2250 625);
DOT 1 (2250 575);
DOT 1 (2250 525);
DOT 1 (2125 925);
DOT 1 (2125 875);
DOT 1 (2125 825);
DOT 1 (2125 775);
DOT 1 (2125 725);
DOT 1 (2125 625);
DOT 1 (2125 675);
DOT 1 (2125 575);
DOT 1 (2125 525);
DOT 1 (2250 475);
DOT 1 (2125 475);
DOT 1 (2250 425);
DOT 1 (2250 375);
DOT 1 (2250 325);
DOT 1 (2250 275);
DOT 1 (2250 225);
DOT 1 (2250 125);
DOT 1 (2250 175);
DOT 1 (2250 75);
DOT 1 (2250 25);
DOT 1 (2250 -25);
DOT 1 (2125 425);
DOT 1 (2125 375);
DOT 1 (2125 325);
DOT 1 (2125 275);
DOT 1 (2125 225);
DOT 1 (2125 125);
DOT 1 (2125 175);
DOT 1 (2125 75);
DOT 1 (2125 -25);
DOT 1 (5150 -75);
DOT 1 (5150 -125);
DOT 1 (5150 -175);
DOT 1 (5150 -225);
DOT 1 (2250 -175);
DOT 1 (2250 -225);
DOT 1 (2125 -75);
DOT 1 (2125 -125);
DOT 1 (2125 -175);
DOT 1 (2125 -225);
DOT 1 (-775 3675);
DOT 1 (-775 3575);
DOT 1 (-775 3625);
DOT 1 (-925 3675);
DOT 1 (-925 3575);
DOT 1 (-925 3625);
DOT 1 (-775 3525);
DOT 1 (-775 3475);
DOT 1 (-775 3425);
DOT 1 (-775 3375);
DOT 1 (-775 3325);
DOT 1 (-775 3275);
DOT 1 (-775 3125);
DOT 1 (-775 3075);
DOT 1 (-925 3475);
DOT 1 (-925 3425);
DOT 1 (-925 3525);
DOT 1 (-925 3325);
DOT 1 (-925 3175);
DOT 1 (-925 3275);
DOT 1 (-925 3225);
DOT 1 (-925 3075);
DOT 1 (-775 3025);
DOT 1 (-925 3025);
DOT 1 (-775 2925);
DOT 1 (-775 2975);
DOT 1 (-775 2825);
DOT 1 (-775 2775);
DOT 1 (-775 2675);
DOT 1 (-775 2725);
DOT 1 (-775 2625);
DOT 1 (-775 2575);
DOT 1 (-775 2525);
DOT 1 (-925 2925);
DOT 1 (-925 2975);
DOT 1 (-925 2875);
DOT 1 (-925 2825);
DOT 1 (-925 2775);
DOT 1 (-925 2675);
DOT 1 (-925 2725);
DOT 1 (-925 2625);
DOT 1 (-925 2575);
DOT 1 (-925 2525);
DOT 1 (-775 2425);
DOT 1 (-775 2475);
DOT 1 (-775 2375);
DOT 1 (-775 2325);
DOT 1 (-775 2275);
DOT 1 (-775 2225);
DOT 1 (-775 2125);
DOT 1 (-775 2075);
DOT 1 (-775 2025);
DOT 1 (-925 2425);
DOT 1 (-925 2475);
DOT 1 (-925 2375);
DOT 1 (-925 2325);
DOT 1 (-925 2275);
DOT 1 (-925 2175);
DOT 1 (-925 2225);
DOT 1 (-925 2075);
DOT 1 (-925 2025);
DOT 1 (-775 1975);
DOT 1 (-775 1925);
DOT 1 (-775 1875);
DOT 1 (-775 1775);
DOT 1 (-775 1725);
DOT 1 (-775 1675);
DOT 1 (-775 1625);
DOT 1 (-775 1525);
DOT 1 (-925 1925);
DOT 1 (-925 1975);
DOT 1 (-925 1875);
DOT 1 (-925 1825);
DOT 1 (-925 1775);
DOT 1 (-925 1675);
DOT 1 (-925 1725);
DOT 1 (-925 1625);
DOT 1 (-925 1575);
DOT 1 (-925 1525);
DOT 1 (-775 1475);
DOT 1 (-775 1425);
DOT 1 (-775 1375);
DOT 1 (-775 1325);
DOT 1 (-775 1275);
DOT 1 (-775 1225);
DOT 1 (-775 1175);
DOT 1 (-775 1125);
DOT 1 (-775 1075);
DOT 1 (-775 1025);
DOT 1 (-925 1425);
DOT 1 (-925 1375);
DOT 1 (-925 1475);
DOT 1 (-925 1325);
DOT 1 (-925 1275);
DOT 1 (-925 1125);
DOT 1 (-925 1175);
DOT 1 (-925 1225);
DOT 1 (-925 1075);
DOT 1 (-925 1025);
DOT 1 (-775 975);
DOT 1 (-925 975);
DOT 1 (-775 875);
DOT 1 (-775 925);
DOT 1 (-775 825);
DOT 1 (-775 775);
DOT 1 (-775 725);
DOT 1 (-775 625);
DOT 1 (-775 675);
DOT 1 (-775 575);
DOT 1 (-775 525);
DOT 1 (-925 925);
DOT 1 (-925 875);
DOT 1 (-925 825);
DOT 1 (-925 775);
DOT 1 (-925 725);
DOT 1 (-925 625);
DOT 1 (-925 675);
DOT 1 (-925 575);
DOT 1 (-925 525);
DOT 1 (-775 475);
DOT 1 (-925 475);
DOT 1 (-775 375);
DOT 1 (-775 425);
DOT 1 (-775 325);
DOT 1 (-775 275);
DOT 1 (-775 225);
DOT 1 (-775 125);
DOT 1 (-775 175);
DOT 1 (-775 75);
DOT 1 (-775 25);
DOT 1 (-775 -25);
DOT 1 (-925 425);
DOT 1 (-925 375);
DOT 1 (-925 225);
DOT 1 (-925 275);
DOT 1 (-925 325);
DOT 1 (-925 125);
DOT 1 (-925 175);
DOT 1 (-925 75);
DOT 1 (-925 25);
DOT 1 (-925 -25);
DOT 1 (-3825 3675);
DOT 1 (-3825 3625);
DOT 1 (-3825 3575);
DOT 1 (-3825 3525);
DOT 1 (-3825 3475);
DOT 1 (-3825 3425);
DOT 1 (-3825 3375);
DOT 1 (-3825 3325);
DOT 1 (-3825 3275);
DOT 1 (-3825 3175);
DOT 1 (-3825 3125);
DOT 1 (-3825 3075);
DOT 1 (-3825 3025);
DOT 1 (-3825 2975);
DOT 1 (-3825 2925);
DOT 1 (-3825 2875);
DOT 1 (-3825 2825);
DOT 1 (-3825 2775);
DOT 1 (-3825 2725);
DOT 1 (-3825 2625);
DOT 1 (-3825 2575);
DOT 1 (-3825 2525);
DOT 1 (-3825 2475);
DOT 1 (-3825 2425);
DOT 1 (-3825 2375);
DOT 1 (-3825 2325);
DOT 1 (-3825 2275);
DOT 1 (-3825 2175);
DOT 1 (-3825 2225);
DOT 1 (-3825 2125);
DOT 1 (-3825 2075);
DOT 1 (-3825 2025);
DOT 1 (-3825 1975);
DOT 1 (-3825 1925);
DOT 1 (-3825 1825);
DOT 1 (-3825 1775);
DOT 1 (-3825 1725);
DOT 1 (-3825 1675);
DOT 1 (-3825 1625);
DOT 1 (-3825 1525);
DOT 1 (-3825 1575);
DOT 1 (-3825 1475);
DOT 1 (-3825 1425);
DOT 1 (-3825 1375);
DOT 1 (-3825 1275);
DOT 1 (-3825 1325);
DOT 1 (-3825 1225);
DOT 1 (-3825 1175);
DOT 1 (-3825 1125);
DOT 1 (-3825 1075);
DOT 1 (-3825 1025);
DOT 1 (-3825 975);
DOT 1 (-3825 925);
DOT 1 (-3825 875);
DOT 1 (-3825 825);
DOT 1 (-3825 775);
DOT 1 (-3825 725);
DOT 1 (-3825 625);
DOT 1 (-3825 675);
DOT 1 (-3825 575);
DOT 1 (-3825 525);
DOT 1 (-3825 475);
DOT 1 (-3825 425);
DOT 1 (-3825 375);
DOT 1 (-3825 325);
DOT 1 (-3825 275);
DOT 1 (-3825 225);
DOT 1 (-3825 175);
DOT 1 (-3825 125);
DOT 1 (-3825 75);
DOT 1 (-3825 25);
DOT 1 (-3825 -25);
DOT 1 (-775 -75);
DOT 1 (-775 -125);
DOT 1 (-775 -175);
DOT 1 (-775 -225);
DOT 1 (-925 -125);
DOT 1 (-925 -75);
DOT 1 (-925 -175);
DOT 1 (-925 -225);
DOT 1 (-3825 -75);
DOT 1 (-3825 -125);
DOT 1 (-3825 -175);
DOT 1 (-3825 -225);
DOT 1 (-775 3175);
DOT 1 (-775 3225);
DOT 1 (-925 3375);
DOT 1 (-925 3125);
QUIT
